G04*
G04 #@! TF.GenerationSoftware,Altium Limited,Altium Designer,23.7.1 (13)*
G04*
G04 Layer_Physical_Order=1*
G04 Layer_Color=255*
%FSLAX25Y25*%
%MOIN*%
G70*
G04*
G04 #@! TF.SameCoordinates,AF00DCEB-AC48-4C7C-91EA-99F42E284231*
G04*
G04*
G04 #@! TF.FilePolarity,Positive*
G04*
G01*
G75*
%ADD11C,0.02000*%
%ADD16C,0.00500*%
%ADD17C,0.01500*%
%ADD18C,0.01000*%
%ADD19C,0.00600*%
%ADD25C,0.00800*%
%ADD32C,0.02500*%
%ADD38R,0.12795X0.12795*%
%ADD39R,0.01024X0.03543*%
%ADD40R,0.03543X0.01024*%
%ADD41R,0.03740X0.03740*%
%ADD42R,0.01772X0.01772*%
%ADD43R,0.04331X0.04134*%
%ADD44R,0.03543X0.02953*%
%ADD45R,0.03543X0.03150*%
%ADD46R,0.04134X0.04331*%
%ADD47R,0.05709X0.04528*%
%ADD48R,0.05709X0.07480*%
%ADD49R,0.05512X0.03937*%
%ADD50R,0.03543X0.03937*%
%ADD51C,0.02918*%
%ADD52R,0.01457X0.00945*%
%ADD53R,0.01575X0.04252*%
%ADD54R,0.07835X0.09173*%
G04:AMPARAMS|DCode=55|XSize=11.81mil|YSize=29.53mil|CornerRadius=1.95mil|HoleSize=0mil|Usage=FLASHONLY|Rotation=180.000|XOffset=0mil|YOffset=0mil|HoleType=Round|Shape=RoundedRectangle|*
%AMROUNDEDRECTD55*
21,1,0.01181,0.02563,0,0,180.0*
21,1,0.00791,0.02953,0,0,180.0*
1,1,0.00390,-0.00396,0.01282*
1,1,0.00390,0.00396,0.01282*
1,1,0.00390,0.00396,-0.01282*
1,1,0.00390,-0.00396,-0.01282*
%
%ADD55ROUNDEDRECTD55*%
G04:AMPARAMS|DCode=56|XSize=11.81mil|YSize=29.53mil|CornerRadius=1.95mil|HoleSize=0mil|Usage=FLASHONLY|Rotation=90.000|XOffset=0mil|YOffset=0mil|HoleType=Round|Shape=RoundedRectangle|*
%AMROUNDEDRECTD56*
21,1,0.01181,0.02563,0,0,90.0*
21,1,0.00791,0.02953,0,0,90.0*
1,1,0.00390,0.01282,0.00396*
1,1,0.00390,0.01282,-0.00396*
1,1,0.00390,-0.01282,-0.00396*
1,1,0.00390,-0.01282,0.00396*
%
%ADD56ROUNDEDRECTD56*%
%ADD57R,0.05315X0.01575*%
%ADD58R,0.07480X0.07087*%
%ADD59R,0.08287X0.04409*%
%ADD60R,0.01968X0.01772*%
%ADD61R,0.03150X0.03150*%
%ADD62R,0.05000X0.02992*%
%ADD63R,0.09600X0.04400*%
%ADD64R,0.02165X0.02165*%
%ADD65R,0.07100X0.07100*%
%ADD66R,0.01000X0.03200*%
%ADD67R,0.03200X0.01000*%
%ADD68R,0.01772X0.01968*%
%ADD69R,0.02165X0.02165*%
%ADD70R,0.06102X0.01181*%
%ADD71R,0.10827X0.04724*%
%ADD72R,0.01181X0.06102*%
%ADD73R,0.04724X0.10827*%
%ADD74R,0.09800X0.03700*%
%ADD75R,0.23300X0.21700*%
%ADD76R,0.00984X0.01870*%
%ADD77R,0.01870X0.01378*%
%ADD78R,0.05100X0.03500*%
%ADD79R,0.08300X0.03500*%
%ADD80R,0.08300X0.07400*%
%ADD81R,0.02600X0.07400*%
%ADD82R,0.01400X0.07400*%
%ADD83R,0.02000X0.01300*%
%ADD84R,0.01300X0.02000*%
%ADD85R,0.09173X0.07835*%
%ADD86R,0.02816X0.02648*%
%ADD87R,0.02016X0.02288*%
%ADD88R,0.02911X0.02648*%
%ADD89R,0.02756X0.02756*%
G04:AMPARAMS|DCode=90|XSize=40.88mil|YSize=20.95mil|CornerRadius=10.48mil|HoleSize=0mil|Usage=FLASHONLY|Rotation=270.000|XOffset=0mil|YOffset=0mil|HoleType=Round|Shape=RoundedRectangle|*
%AMROUNDEDRECTD90*
21,1,0.04088,0.00000,0,0,270.0*
21,1,0.01993,0.02095,0,0,270.0*
1,1,0.02095,0.00000,-0.00996*
1,1,0.02095,0.00000,0.00996*
1,1,0.02095,0.00000,0.00996*
1,1,0.02095,0.00000,-0.00996*
%
%ADD90ROUNDEDRECTD90*%
%ADD91R,0.02095X0.04088*%
G04:AMPARAMS|DCode=92|XSize=61.02mil|YSize=23.62mil|CornerRadius=2.01mil|HoleSize=0mil|Usage=FLASHONLY|Rotation=90.000|XOffset=0mil|YOffset=0mil|HoleType=Round|Shape=RoundedRectangle|*
%AMROUNDEDRECTD92*
21,1,0.06102,0.01961,0,0,90.0*
21,1,0.05701,0.02362,0,0,90.0*
1,1,0.00402,0.00980,0.02850*
1,1,0.00402,0.00980,-0.02850*
1,1,0.00402,-0.00980,-0.02850*
1,1,0.00402,-0.00980,0.02850*
%
%ADD92ROUNDEDRECTD92*%
%ADD93R,0.05906X0.07284*%
G04:AMPARAMS|DCode=94|XSize=61.02mil|YSize=23.62mil|CornerRadius=2.01mil|HoleSize=0mil|Usage=FLASHONLY|Rotation=0.000|XOffset=0mil|YOffset=0mil|HoleType=Round|Shape=RoundedRectangle|*
%AMROUNDEDRECTD94*
21,1,0.06102,0.01961,0,0,0.0*
21,1,0.05701,0.02362,0,0,0.0*
1,1,0.00402,0.02850,-0.00980*
1,1,0.00402,-0.02850,-0.00980*
1,1,0.00402,-0.02850,0.00980*
1,1,0.00402,0.02850,0.00980*
%
%ADD94ROUNDEDRECTD94*%
%ADD95R,0.04546X0.06717*%
%ADD96R,0.03500X0.05100*%
%ADD97R,0.03500X0.08300*%
%ADD98R,0.07400X0.08300*%
%ADD99R,0.07400X0.02600*%
%ADD100R,0.07400X0.01400*%
%ADD101R,0.06717X0.04546*%
%ADD102R,0.04331X0.05315*%
%ADD103R,0.07874X0.11811*%
%ADD104R,0.11811X0.07874*%
%ADD105R,0.02631X0.02648*%
%ADD106R,0.02559X0.02362*%
%ADD107R,0.00984X0.06102*%
%ADD108R,0.05315X0.06693*%
%ADD109O,0.02362X0.08661*%
%ADD110O,0.02362X0.07480*%
%ADD111R,0.07480X0.04331*%
%ADD112R,0.02835X0.02835*%
%ADD113R,0.02648X0.02911*%
%ADD114R,0.04409X0.08287*%
%ADD115R,0.03543X0.01968*%
%ADD116R,0.03740X0.05709*%
%ADD117R,0.04134X0.03937*%
%ADD118R,0.08661X0.04134*%
%ADD119R,0.02362X0.02559*%
%ADD120R,0.02288X0.02016*%
%ADD121R,0.03937X0.05512*%
%ADD122R,0.05512X0.05512*%
%ADD123R,0.14488X0.05000*%
%ADD124R,0.02648X0.02816*%
%ADD125R,0.01378X0.01968*%
%ADD126R,0.03543X0.02362*%
%ADD127R,0.02165X0.02362*%
%ADD128R,0.01870X0.01968*%
G04:AMPARAMS|DCode=129|XSize=33.06mil|YSize=8.76mil|CornerRadius=4.38mil|HoleSize=0mil|Usage=FLASHONLY|Rotation=90.000|XOffset=0mil|YOffset=0mil|HoleType=Round|Shape=RoundedRectangle|*
%AMROUNDEDRECTD129*
21,1,0.03306,0.00000,0,0,90.0*
21,1,0.02430,0.00876,0,0,90.0*
1,1,0.00876,0.00000,0.01215*
1,1,0.00876,0.00000,-0.01215*
1,1,0.00876,0.00000,-0.01215*
1,1,0.00876,0.00000,0.01215*
%
%ADD129ROUNDEDRECTD129*%
%ADD130R,0.00876X0.03306*%
%ADD131R,0.05142X0.04166*%
%ADD132R,0.01968X0.01968*%
%ADD133R,0.09449X0.12992*%
%ADD134R,0.06693X0.05315*%
%ADD135R,0.06102X0.00984*%
%ADD136R,0.07087X0.00984*%
%ADD137R,0.07480X0.05709*%
%ADD138R,0.03347X0.01181*%
%ADD139R,0.03543X0.02756*%
%ADD140R,0.02756X0.03543*%
%ADD141R,0.02800X0.16500*%
%ADD142R,0.02800X0.12600*%
%ADD143R,0.03937X0.02835*%
%ADD144R,0.07480X0.06201*%
%ADD169R,0.02362X0.00787*%
%ADD170R,0.00787X0.02362*%
%ADD171C,0.00709*%
%ADD174R,0.00787X0.02362*%
%ADD175R,0.02362X0.00787*%
%ADD194R,0.10039X0.06496*%
%ADD210C,0.11800*%
%ADD211R,0.10827X0.10827*%
%ADD212C,0.10827*%
%ADD216C,0.00800*%
%ADD217C,0.06299*%
%ADD218C,0.04331*%
G04:AMPARAMS|DCode=230|XSize=82.68mil|YSize=82.68mil|CornerRadius=2.07mil|HoleSize=0mil|Usage=FLASHONLY|Rotation=90.000|XOffset=0mil|YOffset=0mil|HoleType=Round|Shape=RoundedRectangle|*
%AMROUNDEDRECTD230*
21,1,0.08268,0.07854,0,0,90.0*
21,1,0.07854,0.08268,0,0,90.0*
1,1,0.00413,0.03927,0.03927*
1,1,0.00413,0.03927,-0.03927*
1,1,0.00413,-0.03927,-0.03927*
1,1,0.00413,-0.03927,0.03927*
%
%ADD230ROUNDEDRECTD230*%
%ADD231C,0.03000*%
%ADD232C,0.04000*%
%ADD233C,0.05000*%
%ADD234R,0.09478X0.29380*%
%ADD235R,0.09941X0.06791*%
%ADD236C,0.06102*%
%ADD237R,0.06102X0.06102*%
%ADD238R,0.06299X0.06299*%
%ADD239C,0.25000*%
%ADD240O,0.04921X0.04134*%
%ADD241O,0.07480X0.04724*%
%ADD242C,0.25591*%
%ADD243C,0.02166*%
%ADD244C,0.10000*%
%ADD245C,0.24000*%
%ADD246C,0.08661*%
%ADD247R,0.07874X0.07874*%
%ADD248R,0.05906X0.05906*%
%ADD249C,0.05906*%
%ADD250C,0.01600*%
%ADD251C,0.20000*%
G36*
X510723Y14449D02*
X511046D01*
Y14417D01*
X511207D01*
Y14385D01*
X511336D01*
Y14353D01*
X511401D01*
Y14320D01*
X511497D01*
Y14288D01*
X511562D01*
Y14256D01*
X511659D01*
Y14224D01*
X511691D01*
Y14191D01*
X511756D01*
Y14159D01*
X511820D01*
Y14127D01*
X511852D01*
Y14095D01*
X511917D01*
Y14062D01*
X511949D01*
Y14030D01*
X512014D01*
Y13998D01*
X512046D01*
Y13965D01*
X512078D01*
Y13933D01*
X512110D01*
Y13901D01*
X512143D01*
Y13869D01*
X512175D01*
Y13836D01*
X512207D01*
Y13804D01*
X512239D01*
Y13772D01*
X512272D01*
Y13740D01*
X512304D01*
Y13707D01*
X512336D01*
Y13675D01*
X512368D01*
Y13643D01*
Y13611D01*
X512401D01*
Y13578D01*
X512433D01*
Y13546D01*
Y13514D01*
X512465D01*
Y13482D01*
X512498D01*
Y13449D01*
Y13417D01*
X512530D01*
Y13385D01*
Y13352D01*
X512562D01*
Y13320D01*
X512594D01*
Y13288D01*
Y13256D01*
X512627D01*
Y13223D01*
Y13191D01*
Y13159D01*
X512659D01*
Y13127D01*
Y13094D01*
X512691D01*
Y13062D01*
Y13030D01*
Y12998D01*
X512723D01*
Y12965D01*
Y12933D01*
Y12901D01*
Y12869D01*
X512756D01*
Y12836D01*
Y12804D01*
Y12772D01*
Y12740D01*
X512788D01*
Y12707D01*
Y12675D01*
Y12643D01*
Y12610D01*
Y12578D01*
Y12546D01*
Y12514D01*
Y12481D01*
Y12449D01*
Y12417D01*
X512820D01*
Y12385D01*
Y12352D01*
Y12320D01*
Y12288D01*
X512788D01*
Y12256D01*
Y12223D01*
Y12191D01*
Y12159D01*
Y12127D01*
Y12094D01*
Y12062D01*
Y12030D01*
Y11998D01*
X512756D01*
Y11965D01*
Y11933D01*
Y11901D01*
Y11868D01*
Y11836D01*
X512723D01*
Y11804D01*
Y11772D01*
Y11739D01*
X512691D01*
Y11707D01*
Y11675D01*
Y11643D01*
X512659D01*
Y11610D01*
Y11578D01*
Y11546D01*
X512627D01*
Y11514D01*
Y11481D01*
X512594D01*
Y11449D01*
Y11417D01*
X512562D01*
Y11384D01*
Y11352D01*
X512530D01*
Y11320D01*
Y11288D01*
X512498D01*
Y11255D01*
Y11223D01*
X512465D01*
Y11191D01*
X512433D01*
Y11159D01*
Y11126D01*
X512401D01*
Y11094D01*
X512368D01*
Y11062D01*
X512336D01*
Y11030D01*
Y10997D01*
X512304D01*
Y10965D01*
X512272D01*
Y10933D01*
X512239D01*
Y10901D01*
X512207D01*
Y10868D01*
X512175D01*
Y10836D01*
X512143D01*
Y10804D01*
X512110D01*
Y10772D01*
X512078D01*
Y10739D01*
X512014D01*
Y10707D01*
X511981D01*
Y10675D01*
X511949D01*
Y10643D01*
X511917D01*
Y10610D01*
X511852D01*
Y10578D01*
X511820D01*
Y10546D01*
X511756D01*
Y10514D01*
X511691D01*
Y10481D01*
X511626D01*
Y10449D01*
X511562D01*
Y10417D01*
X511497D01*
Y10384D01*
X511401D01*
Y10352D01*
X511304D01*
Y10320D01*
X511175D01*
Y10288D01*
X511014D01*
Y10255D01*
X507884D01*
Y10288D01*
X507723D01*
Y10320D01*
X507626D01*
Y10352D01*
X507529D01*
Y10384D01*
X507432D01*
Y10417D01*
X507368D01*
Y10449D01*
X507271D01*
Y10481D01*
X507239D01*
Y10514D01*
X507174D01*
Y10546D01*
X507110D01*
Y10578D01*
X507078D01*
Y10610D01*
X507013D01*
Y10643D01*
X506981D01*
Y10675D01*
X506916D01*
Y10707D01*
X506884D01*
Y10739D01*
X506852D01*
Y10772D01*
X506819D01*
Y10804D01*
X506787D01*
Y10836D01*
X506755D01*
Y10868D01*
X506723D01*
Y10901D01*
X506690D01*
Y10933D01*
X506658D01*
Y10965D01*
X506626D01*
Y10997D01*
X506594D01*
Y11030D01*
X506561D01*
Y11062D01*
Y11094D01*
X506529D01*
Y11126D01*
X506497D01*
Y11159D01*
X506464D01*
Y11191D01*
Y11223D01*
X506432D01*
Y11255D01*
Y11288D01*
X506400D01*
Y11320D01*
X506368D01*
Y11352D01*
Y11384D01*
X506335D01*
Y11417D01*
Y11449D01*
X506303D01*
Y11481D01*
Y11514D01*
X506271D01*
Y11546D01*
Y11578D01*
Y11610D01*
X506239D01*
Y11643D01*
Y11675D01*
Y11707D01*
X506207D01*
Y11739D01*
Y11772D01*
Y11804D01*
X506174D01*
Y11836D01*
Y11868D01*
Y11901D01*
Y11933D01*
Y11965D01*
X506142D01*
Y11998D01*
Y12030D01*
Y12062D01*
Y12094D01*
Y12127D01*
X506110D01*
Y12159D01*
Y12191D01*
Y12223D01*
Y12256D01*
Y12288D01*
Y12320D01*
Y12352D01*
Y12385D01*
Y12417D01*
Y12449D01*
Y12481D01*
Y12514D01*
Y12546D01*
X506142D01*
Y12578D01*
Y12610D01*
Y12643D01*
Y12675D01*
Y12707D01*
Y12740D01*
Y12772D01*
X506174D01*
Y12804D01*
Y12836D01*
Y12869D01*
Y12901D01*
X506207D01*
Y12933D01*
Y12965D01*
Y12998D01*
Y13030D01*
X506239D01*
Y13062D01*
Y13094D01*
X506271D01*
Y13127D01*
Y13159D01*
Y13191D01*
X506303D01*
Y13223D01*
Y13256D01*
X506335D01*
Y13288D01*
Y13320D01*
X506368D01*
Y13352D01*
Y13385D01*
X506400D01*
Y13417D01*
Y13449D01*
X506432D01*
Y13482D01*
X506464D01*
Y13514D01*
Y13546D01*
X506497D01*
Y13578D01*
X506529D01*
Y13611D01*
Y13643D01*
X506561D01*
Y13675D01*
X506594D01*
Y13707D01*
X506626D01*
Y13740D01*
X506658D01*
Y13772D01*
X506690D01*
Y13804D01*
X506723D01*
Y13836D01*
X506755D01*
Y13869D01*
X506787D01*
Y13901D01*
X506819D01*
Y13933D01*
X506852D01*
Y13965D01*
X506884D01*
Y13998D01*
X506916D01*
Y14030D01*
X506949D01*
Y14062D01*
X507013D01*
Y14095D01*
X507045D01*
Y14127D01*
X507110D01*
Y14159D01*
X507142D01*
Y14191D01*
X507207D01*
Y14224D01*
X507271D01*
Y14256D01*
X507336D01*
Y14288D01*
X507432D01*
Y14320D01*
X507497D01*
Y14353D01*
X507594D01*
Y14385D01*
X507723D01*
Y14417D01*
X507852D01*
Y14449D01*
X508207D01*
Y14482D01*
X510659D01*
Y14449D01*
X510691D01*
Y14482D01*
X510723D01*
Y14449D01*
D02*
G37*
G36*
X461846Y964D02*
X461976D01*
Y932D01*
X462072D01*
Y900D01*
X462137D01*
Y867D01*
X462201D01*
Y835D01*
X462234D01*
Y803D01*
X462298D01*
Y770D01*
X462330D01*
Y738D01*
X462395D01*
Y706D01*
X462427D01*
Y674D01*
X462460D01*
Y641D01*
X462492D01*
Y609D01*
X462524D01*
Y577D01*
X462556D01*
Y545D01*
Y512D01*
X462589D01*
Y480D01*
X462621D01*
Y448D01*
Y416D01*
X462653D01*
Y383D01*
X462685D01*
Y351D01*
Y319D01*
X462718D01*
Y286D01*
Y254D01*
Y222D01*
X462750D01*
Y190D01*
Y157D01*
Y125D01*
X462782D01*
Y93D01*
Y61D01*
Y28D01*
Y-4D01*
X462814D01*
Y-36D01*
Y-68D01*
Y-101D01*
Y-133D01*
Y-165D01*
Y-197D01*
Y-230D01*
Y-262D01*
Y-294D01*
Y-326D01*
Y-359D01*
Y-391D01*
Y-423D01*
X462782D01*
Y-455D01*
Y-488D01*
Y-520D01*
Y-552D01*
X462750D01*
Y-585D01*
Y-617D01*
Y-649D01*
X462718D01*
Y-681D01*
Y-714D01*
X462685D01*
Y-746D01*
Y-778D01*
X462653D01*
Y-810D01*
Y-843D01*
X462621D01*
Y-875D01*
X462589D01*
Y-907D01*
Y-939D01*
X462556D01*
Y-972D01*
X462524D01*
Y-1004D01*
X462492D01*
Y-1036D01*
X462460D01*
Y-1068D01*
X462427D01*
Y-1101D01*
X462395D01*
Y-1133D01*
X462363D01*
Y-1165D01*
X462330D01*
Y-1198D01*
X462266D01*
Y-1230D01*
X462234D01*
Y-1262D01*
X462169D01*
Y-1294D01*
X462105D01*
Y-1327D01*
X462008D01*
Y-1359D01*
X461911D01*
Y-1391D01*
X461718D01*
Y-1423D01*
X461492D01*
Y-1391D01*
X461298D01*
Y-1359D01*
X461201D01*
Y-1327D01*
X461137D01*
Y-1294D01*
X461040D01*
Y-1262D01*
X461008D01*
Y-1230D01*
X460943D01*
Y-1198D01*
X460911D01*
Y-1165D01*
X460846D01*
Y-1133D01*
X460814D01*
Y-1101D01*
X460782D01*
Y-1068D01*
X460750D01*
Y-1036D01*
X460717D01*
Y-1004D01*
X460685D01*
Y-972D01*
X460653D01*
Y-939D01*
X460620D01*
Y-907D01*
Y-875D01*
X460588D01*
Y-843D01*
Y-810D01*
X460556D01*
Y-778D01*
X460524D01*
Y-746D01*
Y-714D01*
X460492D01*
Y-681D01*
Y-649D01*
Y-617D01*
X460459D01*
Y-585D01*
Y-552D01*
Y-520D01*
X460427D01*
Y-488D01*
Y-455D01*
Y-423D01*
Y-391D01*
Y-359D01*
X460395D01*
Y-326D01*
Y-294D01*
Y-262D01*
Y-230D01*
Y-197D01*
Y-165D01*
Y-133D01*
Y-101D01*
Y-68D01*
Y-36D01*
X460427D01*
Y-4D01*
Y28D01*
Y61D01*
Y93D01*
Y125D01*
X460459D01*
Y157D01*
Y190D01*
Y222D01*
X460492D01*
Y254D01*
Y286D01*
X460524D01*
Y319D01*
Y351D01*
X460556D01*
Y383D01*
Y416D01*
X460588D01*
Y448D01*
Y480D01*
X460620D01*
Y512D01*
X460653D01*
Y545D01*
X460685D01*
Y577D01*
Y609D01*
X460717D01*
Y641D01*
X460750D01*
Y674D01*
X460782D01*
Y706D01*
X460846D01*
Y738D01*
X460879D01*
Y770D01*
X460911D01*
Y803D01*
X460975D01*
Y835D01*
X461008D01*
Y867D01*
X461072D01*
Y900D01*
X461169D01*
Y932D01*
X461234D01*
Y964D01*
X461363D01*
Y996D01*
X461846D01*
Y964D01*
D02*
G37*
G36*
X461814Y-3391D02*
X461943D01*
Y-3424D01*
X462040D01*
Y-3456D01*
X462105D01*
Y-3488D01*
X462169D01*
Y-3520D01*
X462234D01*
Y-3553D01*
X462298D01*
Y-3585D01*
X462330D01*
Y-3617D01*
X462363D01*
Y-3650D01*
X462427D01*
Y-3682D01*
X462460D01*
Y-3714D01*
X462492D01*
Y-3746D01*
X462524D01*
Y-3779D01*
Y-3811D01*
X462556D01*
Y-3843D01*
X462589D01*
Y-3875D01*
X462621D01*
Y-3907D01*
Y-3940D01*
X462653D01*
Y-3972D01*
Y-4004D01*
X462685D01*
Y-4037D01*
Y-4069D01*
X462718D01*
Y-4101D01*
Y-4133D01*
X462750D01*
Y-4166D01*
Y-4198D01*
Y-4230D01*
X462782D01*
Y-4262D01*
Y-4295D01*
Y-4327D01*
Y-4359D01*
X462814D01*
Y-4391D01*
Y-4424D01*
Y-4456D01*
Y-4488D01*
Y-4521D01*
Y-4553D01*
Y-4585D01*
Y-4617D01*
Y-4650D01*
Y-4682D01*
Y-4714D01*
Y-4746D01*
Y-4779D01*
X462782D01*
Y-4811D01*
Y-4843D01*
Y-4875D01*
Y-4908D01*
X462750D01*
Y-4940D01*
Y-4972D01*
Y-5004D01*
X462718D01*
Y-5037D01*
Y-5069D01*
X462685D01*
Y-5101D01*
Y-5133D01*
X462653D01*
Y-5166D01*
Y-5198D01*
X462621D01*
Y-5230D01*
Y-5263D01*
X462589D01*
Y-5295D01*
X462556D01*
Y-5327D01*
X462524D01*
Y-5359D01*
Y-5392D01*
X462492D01*
Y-5424D01*
X462460D01*
Y-5456D01*
X462395D01*
Y-5488D01*
X462363D01*
Y-5521D01*
X462330D01*
Y-5553D01*
X462298D01*
Y-5585D01*
X462234D01*
Y-5617D01*
X462169D01*
Y-5650D01*
X462105D01*
Y-5682D01*
X462040D01*
Y-5714D01*
X461943D01*
Y-5746D01*
X461782D01*
Y-5779D01*
X461427D01*
Y-5746D01*
X461266D01*
Y-5714D01*
X461169D01*
Y-5682D01*
X461104D01*
Y-5650D01*
X461040D01*
Y-5617D01*
X460975D01*
Y-5585D01*
X460943D01*
Y-5553D01*
X460879D01*
Y-5521D01*
X460846D01*
Y-5488D01*
X460814D01*
Y-5456D01*
X460782D01*
Y-5424D01*
X460750D01*
Y-5392D01*
X460717D01*
Y-5359D01*
X460685D01*
Y-5327D01*
X460653D01*
Y-5295D01*
X460620D01*
Y-5263D01*
Y-5230D01*
X460588D01*
Y-5198D01*
X460556D01*
Y-5166D01*
Y-5133D01*
X460524D01*
Y-5101D01*
Y-5069D01*
X460492D01*
Y-5037D01*
Y-5004D01*
Y-4972D01*
X460459D01*
Y-4940D01*
Y-4908D01*
Y-4875D01*
X460427D01*
Y-4843D01*
Y-4811D01*
Y-4779D01*
Y-4746D01*
X460395D01*
Y-4714D01*
Y-4682D01*
Y-4650D01*
Y-4617D01*
Y-4585D01*
Y-4553D01*
Y-4521D01*
Y-4488D01*
Y-4456D01*
Y-4424D01*
Y-4391D01*
X460427D01*
Y-4359D01*
Y-4327D01*
Y-4295D01*
Y-4262D01*
X460459D01*
Y-4230D01*
Y-4198D01*
Y-4166D01*
Y-4133D01*
X460492D01*
Y-4101D01*
Y-4069D01*
X460524D01*
Y-4037D01*
Y-4004D01*
X460556D01*
Y-3972D01*
Y-3940D01*
X460588D01*
Y-3907D01*
X460620D01*
Y-3875D01*
Y-3843D01*
X460653D01*
Y-3811D01*
X460685D01*
Y-3779D01*
X460717D01*
Y-3746D01*
X460750D01*
Y-3714D01*
X460782D01*
Y-3682D01*
X460814D01*
Y-3650D01*
X460846D01*
Y-3617D01*
X460879D01*
Y-3585D01*
X460943D01*
Y-3553D01*
X460975D01*
Y-3520D01*
X461040D01*
Y-3488D01*
X461104D01*
Y-3456D01*
X461169D01*
Y-3424D01*
X461266D01*
Y-3391D01*
X461427D01*
Y-3359D01*
X461814D01*
Y-3391D01*
D02*
G37*
G36*
X518143Y-2391D02*
X518337D01*
Y-2424D01*
X518466D01*
Y-2456D01*
X518563D01*
Y-2488D01*
X518659D01*
Y-2520D01*
X518724D01*
Y-2553D01*
X518821D01*
Y-2585D01*
X518885D01*
Y-2617D01*
X518918D01*
Y-2649D01*
X518982D01*
Y-2682D01*
X519047D01*
Y-2714D01*
X519079D01*
Y-2746D01*
X519143D01*
Y-2778D01*
X519176D01*
Y-2811D01*
X519208D01*
Y-2843D01*
X519240D01*
Y-2875D01*
X519305D01*
Y-2907D01*
X519337D01*
Y-2940D01*
X519369D01*
Y-2972D01*
X519402D01*
Y-3004D01*
X519434D01*
Y-3036D01*
X519466D01*
Y-3069D01*
X519498D01*
Y-3101D01*
X519531D01*
Y-3133D01*
Y-3165D01*
X519563D01*
Y-3198D01*
X519595D01*
Y-3230D01*
X519627D01*
Y-3262D01*
Y-3295D01*
X519660D01*
Y-3327D01*
X519692D01*
Y-3359D01*
Y-3391D01*
X519724D01*
Y-3424D01*
Y-3456D01*
X519756D01*
Y-3488D01*
X519789D01*
Y-3520D01*
Y-3553D01*
X519821D01*
Y-3585D01*
Y-3617D01*
Y-3650D01*
X519853D01*
Y-3682D01*
Y-3714D01*
X519885D01*
Y-3746D01*
Y-3779D01*
Y-3811D01*
X519918D01*
Y-3843D01*
Y-3875D01*
Y-3907D01*
X519950D01*
Y-3940D01*
Y-3972D01*
Y-4004D01*
Y-4037D01*
X519982D01*
Y-4069D01*
Y-4101D01*
Y-4133D01*
Y-4166D01*
Y-4198D01*
Y-4230D01*
X520014D01*
Y-4262D01*
Y-4295D01*
Y-4327D01*
Y-4359D01*
Y-4391D01*
Y-4424D01*
Y-4456D01*
Y-4488D01*
Y-4521D01*
Y-4553D01*
Y-4585D01*
Y-4617D01*
Y-4650D01*
Y-4682D01*
Y-4714D01*
X519982D01*
Y-4746D01*
Y-4779D01*
Y-4811D01*
Y-4843D01*
Y-4875D01*
Y-4908D01*
X519950D01*
Y-4940D01*
Y-4972D01*
Y-5004D01*
Y-5037D01*
X519918D01*
Y-5069D01*
Y-5101D01*
Y-5133D01*
X519885D01*
Y-5166D01*
Y-5198D01*
Y-5230D01*
X519853D01*
Y-5263D01*
Y-5295D01*
X519821D01*
Y-5327D01*
Y-5359D01*
X519789D01*
Y-5392D01*
Y-5424D01*
X519756D01*
Y-5456D01*
Y-5488D01*
X519724D01*
Y-5521D01*
Y-5553D01*
X519692D01*
Y-5585D01*
X519660D01*
Y-5617D01*
Y-5650D01*
X519627D01*
Y-5682D01*
X519595D01*
Y-5714D01*
Y-5746D01*
X519563D01*
Y-5779D01*
X519531D01*
Y-5811D01*
X519498D01*
Y-5843D01*
X519466D01*
Y-5875D01*
X519434D01*
Y-5908D01*
X519402D01*
Y-5940D01*
X519369D01*
Y-5972D01*
X519337D01*
Y-6005D01*
X519305D01*
Y-6037D01*
X519273D01*
Y-6069D01*
X519240D01*
Y-6101D01*
X519208D01*
Y-6134D01*
X519143D01*
Y-6166D01*
X519111D01*
Y-6198D01*
X519079D01*
Y-6230D01*
X519014D01*
Y-6263D01*
X518950D01*
Y-6295D01*
X518918D01*
Y-6327D01*
X518853D01*
Y-6359D01*
X518789D01*
Y-6392D01*
X518692D01*
Y-6424D01*
X518627D01*
Y-6456D01*
X518531D01*
Y-6488D01*
X518401D01*
Y-6521D01*
X518240D01*
Y-6553D01*
X518047D01*
Y-6585D01*
X518014D01*
Y-6553D01*
X517982D01*
Y-6585D01*
X517950D01*
Y-6553D01*
X517917D01*
Y-6585D01*
X517692D01*
Y-6553D01*
X517466D01*
Y-6521D01*
X517305D01*
Y-6488D01*
X517208D01*
Y-6456D01*
X517111D01*
Y-6424D01*
X517014D01*
Y-6392D01*
X516950D01*
Y-6359D01*
X516885D01*
Y-6327D01*
X516821D01*
Y-6295D01*
X516756D01*
Y-6263D01*
X516724D01*
Y-6230D01*
X516659D01*
Y-6198D01*
X516627D01*
Y-6166D01*
X516563D01*
Y-6134D01*
X516530D01*
Y-6101D01*
X516498D01*
Y-6069D01*
X516466D01*
Y-6037D01*
X516401D01*
Y-6005D01*
X516369D01*
Y-5972D01*
X516337D01*
Y-5940D01*
X516304D01*
Y-5908D01*
X516272D01*
Y-5875D01*
X516240D01*
Y-5843D01*
Y-5811D01*
X516208D01*
Y-5779D01*
X516175D01*
Y-5746D01*
X516143D01*
Y-5714D01*
X516111D01*
Y-5682D01*
Y-5650D01*
X516079D01*
Y-5617D01*
X516046D01*
Y-5585D01*
Y-5553D01*
X516014D01*
Y-5521D01*
Y-5488D01*
X515982D01*
Y-5456D01*
X515949D01*
Y-5424D01*
Y-5392D01*
X515917D01*
Y-5359D01*
Y-5327D01*
X515885D01*
Y-5295D01*
Y-5263D01*
Y-5230D01*
X515853D01*
Y-5198D01*
Y-5166D01*
X515821D01*
Y-5133D01*
Y-5101D01*
Y-5069D01*
X515788D01*
Y-5037D01*
Y-5004D01*
Y-4972D01*
Y-4940D01*
X515756D01*
Y-4908D01*
Y-4875D01*
Y-4843D01*
Y-4811D01*
Y-4779D01*
X515724D01*
Y-4746D01*
Y-4714D01*
Y-4682D01*
Y-4650D01*
Y-4617D01*
Y-4585D01*
Y-4553D01*
Y-4521D01*
Y-4488D01*
Y-4456D01*
Y-4424D01*
Y-4391D01*
Y-4359D01*
Y-4327D01*
Y-4295D01*
Y-4262D01*
Y-4230D01*
Y-4198D01*
Y-4166D01*
X515756D01*
Y-4133D01*
Y-4101D01*
Y-4069D01*
Y-4037D01*
Y-4004D01*
X515788D01*
Y-3972D01*
Y-3940D01*
Y-3907D01*
Y-3875D01*
X515821D01*
Y-3843D01*
Y-3811D01*
Y-3779D01*
X515853D01*
Y-3746D01*
Y-3714D01*
Y-3682D01*
X515885D01*
Y-3650D01*
Y-3617D01*
X515917D01*
Y-3585D01*
Y-3553D01*
X515949D01*
Y-3520D01*
Y-3488D01*
X515982D01*
Y-3456D01*
Y-3424D01*
X516014D01*
Y-3391D01*
Y-3359D01*
X516046D01*
Y-3327D01*
X516079D01*
Y-3295D01*
Y-3262D01*
X516111D01*
Y-3230D01*
X516143D01*
Y-3198D01*
X516175D01*
Y-3165D01*
Y-3133D01*
X516208D01*
Y-3101D01*
X516240D01*
Y-3069D01*
X516272D01*
Y-3036D01*
X516304D01*
Y-3004D01*
X516337D01*
Y-2972D01*
X516369D01*
Y-2940D01*
X516401D01*
Y-2907D01*
X516433D01*
Y-2875D01*
X516466D01*
Y-2843D01*
X516498D01*
Y-2811D01*
X516563D01*
Y-2778D01*
X516595D01*
Y-2746D01*
X516659D01*
Y-2714D01*
X516691D01*
Y-2682D01*
X516756D01*
Y-2649D01*
X516788D01*
Y-2617D01*
X516853D01*
Y-2585D01*
X516917D01*
Y-2553D01*
X516982D01*
Y-2520D01*
X517079D01*
Y-2488D01*
X517175D01*
Y-2456D01*
X517272D01*
Y-2424D01*
X517401D01*
Y-2391D01*
X517563D01*
Y-2359D01*
X518143D01*
Y-2391D01*
D02*
G37*
G36*
X501012Y14449D02*
X501367D01*
Y14417D01*
X501496D01*
Y14385D01*
X501625D01*
Y14353D01*
X501722D01*
Y14320D01*
X501819D01*
Y14288D01*
X501883D01*
Y14256D01*
X501948D01*
Y14224D01*
X502012D01*
Y14191D01*
X502077D01*
Y14159D01*
X502142D01*
Y14127D01*
X502174D01*
Y14095D01*
X502238D01*
Y14062D01*
X502271D01*
Y14030D01*
X502303D01*
Y13998D01*
X502367D01*
Y13965D01*
X502400D01*
Y13933D01*
X502432D01*
Y13901D01*
X502464D01*
Y13869D01*
X502496D01*
Y13836D01*
X502529D01*
Y13804D01*
X502561D01*
Y13772D01*
X502593D01*
Y13740D01*
X502625D01*
Y13707D01*
X502658D01*
Y13675D01*
X502690D01*
Y13643D01*
Y13611D01*
X502722D01*
Y13578D01*
X502754D01*
Y13546D01*
X502787D01*
Y13514D01*
Y13482D01*
X502819D01*
Y13449D01*
Y13417D01*
X502851D01*
Y13385D01*
X502883D01*
Y13352D01*
Y13320D01*
X502916D01*
Y13288D01*
Y13256D01*
X502948D01*
Y13223D01*
Y13191D01*
X502980D01*
Y13159D01*
Y13127D01*
Y13094D01*
X503013D01*
Y13062D01*
Y13030D01*
Y12998D01*
X503045D01*
Y12965D01*
Y12933D01*
Y12901D01*
X503077D01*
Y12869D01*
Y12836D01*
Y12804D01*
Y12772D01*
X503109D01*
Y12740D01*
Y12707D01*
Y12675D01*
Y12643D01*
Y12610D01*
Y12578D01*
X503142D01*
Y12546D01*
Y12514D01*
Y12481D01*
Y12449D01*
Y12417D01*
Y12385D01*
Y12352D01*
Y12320D01*
Y12288D01*
Y12256D01*
Y12223D01*
X503109D01*
Y12191D01*
X503142D01*
Y12159D01*
X503109D01*
Y12127D01*
Y12094D01*
Y12062D01*
Y12030D01*
Y11998D01*
Y11965D01*
Y11933D01*
X503077D01*
Y11901D01*
Y11868D01*
Y11836D01*
Y11804D01*
X503045D01*
Y11772D01*
Y11739D01*
Y11707D01*
X503013D01*
Y11675D01*
Y11643D01*
Y11610D01*
X502980D01*
Y11578D01*
Y11546D01*
Y11514D01*
X502948D01*
Y11481D01*
Y11449D01*
X502916D01*
Y11417D01*
Y11384D01*
X502883D01*
Y11352D01*
Y11320D01*
X502851D01*
Y11288D01*
X502819D01*
Y11255D01*
Y11223D01*
X502787D01*
Y11191D01*
X502754D01*
Y11159D01*
Y11126D01*
X502722D01*
Y11094D01*
X502690D01*
Y11062D01*
X502658D01*
Y11030D01*
Y10997D01*
X502625D01*
Y10965D01*
X502593D01*
Y10933D01*
X502561D01*
Y10901D01*
X502529D01*
Y10868D01*
X502496D01*
Y10836D01*
X502464D01*
Y10804D01*
X502432D01*
Y10772D01*
X502400D01*
Y10739D01*
X502335D01*
Y10707D01*
X502303D01*
Y10675D01*
X502271D01*
Y10643D01*
X502206D01*
Y10610D01*
X502174D01*
Y10578D01*
X502109D01*
Y10546D01*
X502077D01*
Y10514D01*
X502012D01*
Y10481D01*
X501948D01*
Y10449D01*
X501883D01*
Y10417D01*
X501787D01*
Y10384D01*
X501722D01*
Y10352D01*
X501593D01*
Y10320D01*
X501496D01*
Y10288D01*
X501303D01*
Y10255D01*
X496431D01*
Y10223D01*
X496173D01*
Y10191D01*
X496044D01*
Y10159D01*
X495915D01*
Y10126D01*
X495850D01*
Y10094D01*
X495754D01*
Y10062D01*
X495689D01*
Y10029D01*
X495625D01*
Y9997D01*
X495560D01*
Y9965D01*
X495496D01*
Y9933D01*
X495463D01*
Y9900D01*
X495399D01*
Y9868D01*
X495334D01*
Y9836D01*
X495302D01*
Y9804D01*
X495270D01*
Y9771D01*
X495237D01*
Y9739D01*
X495173D01*
Y9707D01*
X495141D01*
Y9675D01*
X495108D01*
Y9642D01*
X495076D01*
Y9610D01*
X495044D01*
Y9578D01*
X495012D01*
Y9546D01*
X494979D01*
Y9513D01*
X494947D01*
Y9481D01*
Y9449D01*
X494915D01*
Y9417D01*
X494883D01*
Y9384D01*
X494850D01*
Y9352D01*
Y9320D01*
X494818D01*
Y9287D01*
X494786D01*
Y9255D01*
Y9223D01*
X494754D01*
Y9191D01*
X494721D01*
Y9159D01*
Y9126D01*
X494689D01*
Y9094D01*
Y9062D01*
X494657D01*
Y9029D01*
Y8997D01*
X494625D01*
Y8965D01*
Y8933D01*
Y8900D01*
X494592D01*
Y8868D01*
Y8836D01*
X494560D01*
Y8804D01*
Y8771D01*
Y8739D01*
X494528D01*
Y8707D01*
Y8675D01*
Y8642D01*
Y8610D01*
X494495D01*
Y8578D01*
Y8546D01*
Y8513D01*
Y8481D01*
Y8449D01*
Y8416D01*
X494463D01*
Y8384D01*
Y8352D01*
Y8320D01*
Y8287D01*
Y8255D01*
Y8223D01*
Y8191D01*
Y8158D01*
Y8126D01*
Y8094D01*
Y8062D01*
Y8029D01*
Y7997D01*
Y7965D01*
Y7932D01*
Y7900D01*
X494495D01*
Y7868D01*
Y7836D01*
Y7803D01*
Y7771D01*
Y7739D01*
Y7707D01*
X494528D01*
Y7674D01*
Y7642D01*
Y7610D01*
Y7578D01*
X494560D01*
Y7545D01*
Y7513D01*
Y7481D01*
X494592D01*
Y7449D01*
Y7416D01*
Y7384D01*
X494625D01*
Y7352D01*
Y7320D01*
X494657D01*
Y7287D01*
Y7255D01*
X494689D01*
Y7223D01*
Y7191D01*
X494721D01*
Y7158D01*
Y7126D01*
X494754D01*
Y7094D01*
Y7062D01*
X494786D01*
Y7029D01*
X494818D01*
Y6997D01*
Y6965D01*
X494850D01*
Y6932D01*
X494883D01*
Y6900D01*
Y6868D01*
X494915D01*
Y6836D01*
X494947D01*
Y6803D01*
X494979D01*
Y6771D01*
X495012D01*
Y6739D01*
X495044D01*
Y6707D01*
X495076D01*
Y6674D01*
X495108D01*
Y6642D01*
X495141D01*
Y6610D01*
X495173D01*
Y6577D01*
X495205D01*
Y6545D01*
X495237D01*
Y6513D01*
X495270D01*
Y6481D01*
X495334D01*
Y6448D01*
X495366D01*
Y6416D01*
X495431D01*
Y6384D01*
X495463D01*
Y6352D01*
X495528D01*
Y6319D01*
X495592D01*
Y6287D01*
X495657D01*
Y6255D01*
X495721D01*
Y6223D01*
X495786D01*
Y6190D01*
X495883D01*
Y6158D01*
X495979D01*
Y6126D01*
X496108D01*
Y6094D01*
X496270D01*
Y6061D01*
X521789D01*
Y6029D01*
X521821D01*
Y6061D01*
X521853D01*
Y6029D01*
X522079D01*
Y5997D01*
X522208D01*
Y5965D01*
X522305D01*
Y5932D01*
X522402D01*
Y5900D01*
X522499D01*
Y5868D01*
X522563D01*
Y5835D01*
X522628D01*
Y5803D01*
X522692D01*
Y5771D01*
X522757D01*
Y5739D01*
X522789D01*
Y5706D01*
X522854D01*
Y5674D01*
X522886D01*
Y5642D01*
X522950D01*
Y5610D01*
X522983D01*
Y5577D01*
X523015D01*
Y5545D01*
X523047D01*
Y5513D01*
X523112D01*
Y5481D01*
X523144D01*
Y5448D01*
X523176D01*
Y5416D01*
X523208D01*
Y5384D01*
X523241D01*
Y5352D01*
X523273D01*
Y5319D01*
Y5287D01*
X523305D01*
Y5255D01*
X523338D01*
Y5223D01*
X523370D01*
Y5190D01*
X523402D01*
Y5158D01*
Y5126D01*
X523434D01*
Y5094D01*
X523466D01*
Y5061D01*
Y5029D01*
X523499D01*
Y4997D01*
X523531D01*
Y4964D01*
Y4932D01*
X523563D01*
Y4900D01*
Y4868D01*
X523596D01*
Y4835D01*
Y4803D01*
X523628D01*
Y4771D01*
Y4739D01*
Y4706D01*
X523660D01*
Y4674D01*
Y4642D01*
X523692D01*
Y4610D01*
Y4577D01*
Y4545D01*
X523725D01*
Y4513D01*
Y4481D01*
Y4448D01*
Y4416D01*
X523757D01*
Y4384D01*
Y4352D01*
Y4319D01*
Y4287D01*
Y4255D01*
X523789D01*
Y4222D01*
Y4190D01*
Y4158D01*
Y4126D01*
Y4093D01*
Y4061D01*
Y4029D01*
Y3997D01*
Y3964D01*
Y3932D01*
Y3900D01*
Y3867D01*
Y3835D01*
Y3803D01*
Y3771D01*
Y3739D01*
Y3706D01*
Y3674D01*
Y3642D01*
X523757D01*
Y3609D01*
Y3577D01*
Y3545D01*
Y3513D01*
Y3480D01*
X523725D01*
Y3448D01*
Y3416D01*
Y3384D01*
Y3351D01*
X523692D01*
Y3319D01*
Y3287D01*
Y3255D01*
X523660D01*
Y3222D01*
Y3190D01*
Y3158D01*
X523628D01*
Y3125D01*
Y3093D01*
X523596D01*
Y3061D01*
Y3029D01*
X523563D01*
Y2997D01*
Y2964D01*
X523531D01*
Y2932D01*
Y2900D01*
X523499D01*
Y2867D01*
Y2835D01*
X523466D01*
Y2803D01*
X523434D01*
Y2771D01*
Y2738D01*
X523402D01*
Y2706D01*
X523370D01*
Y2674D01*
X523338D01*
Y2642D01*
X523305D01*
Y2609D01*
Y2577D01*
X523273D01*
Y2545D01*
X523241D01*
Y2513D01*
X523208D01*
Y2480D01*
X523176D01*
Y2448D01*
X523144D01*
Y2416D01*
X523112D01*
Y2383D01*
X523079D01*
Y2351D01*
X523047D01*
Y2319D01*
X522983D01*
Y2287D01*
X522950D01*
Y2254D01*
X522918D01*
Y2222D01*
X522854D01*
Y2190D01*
X522821D01*
Y2158D01*
X522757D01*
Y2125D01*
X522692D01*
Y2093D01*
X522660D01*
Y2061D01*
X522563D01*
Y2029D01*
X522499D01*
Y1996D01*
X522434D01*
Y1964D01*
X522337D01*
Y1932D01*
X522241D01*
Y1900D01*
X522112D01*
Y1867D01*
X521918D01*
Y1835D01*
X505174D01*
Y1803D01*
X504981D01*
Y1770D01*
X504851D01*
Y1738D01*
X504722D01*
Y1706D01*
X504658D01*
Y1674D01*
X504561D01*
Y1641D01*
X504497D01*
Y1609D01*
X504432D01*
Y1577D01*
X504367D01*
Y1545D01*
X504303D01*
Y1512D01*
X504271D01*
Y1480D01*
X504206D01*
Y1448D01*
X504174D01*
Y1416D01*
X504142D01*
Y1383D01*
X504077D01*
Y1351D01*
X504045D01*
Y1319D01*
X504013D01*
Y1287D01*
X503980D01*
Y1254D01*
X503948D01*
Y1222D01*
X503916D01*
Y1190D01*
X503884D01*
Y1158D01*
X503851D01*
Y1125D01*
X503819D01*
Y1093D01*
X503787D01*
Y1061D01*
X503755D01*
Y1029D01*
X503722D01*
Y996D01*
Y964D01*
X503690D01*
Y932D01*
X503658D01*
Y900D01*
Y867D01*
X503625D01*
Y835D01*
X503593D01*
Y803D01*
Y770D01*
X503561D01*
Y738D01*
Y706D01*
X503529D01*
Y674D01*
Y641D01*
X503497D01*
Y609D01*
Y577D01*
X503464D01*
Y545D01*
Y512D01*
X503432D01*
Y480D01*
Y448D01*
Y416D01*
X503400D01*
Y383D01*
Y351D01*
Y319D01*
X503367D01*
Y286D01*
Y254D01*
Y222D01*
Y190D01*
X503335D01*
Y157D01*
Y125D01*
Y93D01*
Y61D01*
Y28D01*
Y-4D01*
X503303D01*
Y-36D01*
Y-68D01*
Y-101D01*
Y-133D01*
Y-165D01*
Y-197D01*
Y-230D01*
Y-262D01*
Y-294D01*
Y-326D01*
Y-359D01*
Y-391D01*
Y-423D01*
Y-455D01*
Y-488D01*
Y-520D01*
X503335D01*
Y-552D01*
Y-585D01*
Y-617D01*
Y-649D01*
Y-681D01*
Y-714D01*
X503367D01*
Y-746D01*
Y-778D01*
Y-810D01*
Y-843D01*
X503400D01*
Y-875D01*
Y-907D01*
Y-939D01*
X503432D01*
Y-972D01*
Y-1004D01*
Y-1036D01*
X503464D01*
Y-1068D01*
Y-1101D01*
X503497D01*
Y-1133D01*
Y-1165D01*
X503529D01*
Y-1198D01*
Y-1230D01*
X503561D01*
Y-1262D01*
Y-1294D01*
X503593D01*
Y-1327D01*
Y-1359D01*
X503625D01*
Y-1391D01*
X503658D01*
Y-1423D01*
Y-1456D01*
X503690D01*
Y-1488D01*
X503722D01*
Y-1520D01*
X503755D01*
Y-1552D01*
Y-1585D01*
X503787D01*
Y-1617D01*
X503819D01*
Y-1649D01*
X503851D01*
Y-1681D01*
X503884D01*
Y-1714D01*
X503916D01*
Y-1746D01*
X503948D01*
Y-1778D01*
X503980D01*
Y-1811D01*
X504013D01*
Y-1843D01*
X504045D01*
Y-1875D01*
X504109D01*
Y-1907D01*
X504142D01*
Y-1940D01*
X504174D01*
Y-1972D01*
X504239D01*
Y-2004D01*
X504271D01*
Y-2036D01*
X504335D01*
Y-2069D01*
X504400D01*
Y-2101D01*
X504432D01*
Y-2133D01*
X504497D01*
Y-2165D01*
X504593D01*
Y-2198D01*
X504658D01*
Y-2230D01*
X504755D01*
Y-2262D01*
X504851D01*
Y-2294D01*
X504981D01*
Y-2327D01*
X505206D01*
Y-2359D01*
X511401D01*
Y-2391D01*
X511562D01*
Y-2424D01*
X511691D01*
Y-2456D01*
X511788D01*
Y-2488D01*
X511884D01*
Y-2520D01*
X511981D01*
Y-2553D01*
X512046D01*
Y-2585D01*
X512110D01*
Y-2617D01*
X512175D01*
Y-2649D01*
X512239D01*
Y-2682D01*
X512272D01*
Y-2714D01*
X512336D01*
Y-2746D01*
X512368D01*
Y-2778D01*
X512401D01*
Y-2811D01*
X512465D01*
Y-2843D01*
X512498D01*
Y-2875D01*
X512530D01*
Y-2907D01*
X512562D01*
Y-2940D01*
X512594D01*
Y-2972D01*
X512627D01*
Y-3004D01*
X512659D01*
Y-3036D01*
X512691D01*
Y-3069D01*
X512723D01*
Y-3101D01*
X512756D01*
Y-3133D01*
X512788D01*
Y-3165D01*
X512820D01*
Y-3198D01*
Y-3230D01*
X512852D01*
Y-3262D01*
X512885D01*
Y-3295D01*
X512917D01*
Y-3327D01*
Y-3359D01*
X512949D01*
Y-3391D01*
Y-3424D01*
X512981D01*
Y-3456D01*
X513014D01*
Y-3488D01*
Y-3520D01*
X513046D01*
Y-3553D01*
Y-3585D01*
X513078D01*
Y-3617D01*
Y-3650D01*
Y-3682D01*
X513110D01*
Y-3714D01*
Y-3746D01*
X513143D01*
Y-3779D01*
Y-3811D01*
Y-3843D01*
X513175D01*
Y-3875D01*
Y-3907D01*
Y-3940D01*
Y-3972D01*
X513207D01*
Y-4004D01*
Y-4037D01*
Y-4069D01*
Y-4101D01*
Y-4133D01*
X513239D01*
Y-4166D01*
Y-4198D01*
Y-4230D01*
Y-4262D01*
Y-4295D01*
Y-4327D01*
Y-4359D01*
Y-4391D01*
Y-4424D01*
Y-4456D01*
Y-4488D01*
Y-4521D01*
Y-4553D01*
Y-4585D01*
Y-4617D01*
Y-4650D01*
Y-4682D01*
Y-4714D01*
Y-4746D01*
Y-4779D01*
Y-4811D01*
X513207D01*
Y-4843D01*
Y-4875D01*
Y-4908D01*
Y-4940D01*
Y-4972D01*
X513175D01*
Y-5004D01*
Y-5037D01*
Y-5069D01*
X513143D01*
Y-5101D01*
Y-5133D01*
Y-5166D01*
X513110D01*
Y-5198D01*
Y-5230D01*
Y-5263D01*
X513078D01*
Y-5295D01*
Y-5327D01*
X513046D01*
Y-5359D01*
Y-5392D01*
X513014D01*
Y-5424D01*
Y-5456D01*
X512981D01*
Y-5488D01*
Y-5521D01*
X512949D01*
Y-5553D01*
Y-5585D01*
X512917D01*
Y-5617D01*
X512885D01*
Y-5650D01*
Y-5682D01*
X512852D01*
Y-5714D01*
X512820D01*
Y-5746D01*
X512788D01*
Y-5779D01*
X512756D01*
Y-5811D01*
Y-5843D01*
X512723D01*
Y-5875D01*
X512691D01*
Y-5908D01*
X512659D01*
Y-5940D01*
X512627D01*
Y-5972D01*
X512594D01*
Y-6005D01*
X512562D01*
Y-6037D01*
X512530D01*
Y-6069D01*
X512465D01*
Y-6101D01*
X512433D01*
Y-6134D01*
X512401D01*
Y-6166D01*
X512336D01*
Y-6198D01*
X512304D01*
Y-6230D01*
X512239D01*
Y-6263D01*
X512207D01*
Y-6295D01*
X512143D01*
Y-6327D01*
X512078D01*
Y-6359D01*
X512014D01*
Y-6392D01*
X511949D01*
Y-6424D01*
X511852D01*
Y-6456D01*
X511756D01*
Y-6488D01*
X511659D01*
Y-6521D01*
X511497D01*
Y-6553D01*
X511272D01*
Y-6585D01*
X511207D01*
Y-6553D01*
X511175D01*
Y-6585D01*
X501496D01*
Y-6553D01*
X501464D01*
Y-6585D01*
X501141D01*
Y-6617D01*
X500980D01*
Y-6650D01*
X500851D01*
Y-6682D01*
X500754D01*
Y-6714D01*
X500690D01*
Y-6747D01*
X500593D01*
Y-6779D01*
X500528D01*
Y-6811D01*
X500464D01*
Y-6843D01*
X500432D01*
Y-6876D01*
X500367D01*
Y-6908D01*
X500303D01*
Y-6940D01*
X500270D01*
Y-6972D01*
X500206D01*
Y-7005D01*
X500174D01*
Y-7037D01*
X500141D01*
Y-7069D01*
X500109D01*
Y-7102D01*
X500044D01*
Y-7134D01*
X500012D01*
Y-7166D01*
X499980D01*
Y-7198D01*
X499948D01*
Y-7231D01*
X499915D01*
Y-7263D01*
X499883D01*
Y-7295D01*
Y-7327D01*
X499851D01*
Y-7360D01*
X499819D01*
Y-7392D01*
X499786D01*
Y-7424D01*
X499754D01*
Y-7456D01*
Y-7489D01*
X499722D01*
Y-7521D01*
X499690D01*
Y-7553D01*
Y-7585D01*
X499657D01*
Y-7618D01*
X499625D01*
Y-7650D01*
Y-7682D01*
X499593D01*
Y-7714D01*
Y-7747D01*
X499560D01*
Y-7779D01*
Y-7811D01*
X499528D01*
Y-7843D01*
Y-7876D01*
X499496D01*
Y-7908D01*
Y-7940D01*
Y-7972D01*
X499464D01*
Y-8005D01*
Y-8037D01*
Y-8069D01*
X499432D01*
Y-8102D01*
Y-8134D01*
Y-8166D01*
X499399D01*
Y-8198D01*
Y-8231D01*
Y-8263D01*
Y-8295D01*
Y-8327D01*
X499367D01*
Y-8360D01*
Y-8392D01*
Y-8424D01*
Y-8456D01*
Y-8489D01*
Y-8521D01*
Y-8553D01*
Y-8585D01*
Y-8618D01*
Y-8650D01*
Y-8682D01*
Y-8715D01*
Y-8747D01*
Y-8779D01*
Y-8811D01*
Y-8844D01*
Y-8876D01*
Y-8908D01*
Y-8940D01*
Y-8973D01*
Y-9005D01*
X499399D01*
Y-9037D01*
Y-9069D01*
Y-9102D01*
Y-9134D01*
Y-9166D01*
X499432D01*
Y-9199D01*
Y-9231D01*
Y-9263D01*
X499464D01*
Y-9295D01*
Y-9328D01*
Y-9360D01*
X499496D01*
Y-9392D01*
Y-9424D01*
Y-9457D01*
X499528D01*
Y-9489D01*
Y-9521D01*
X499560D01*
Y-9553D01*
Y-9586D01*
X499593D01*
Y-9618D01*
Y-9650D01*
X499625D01*
Y-9682D01*
Y-9715D01*
X499657D01*
Y-9747D01*
Y-9779D01*
X499690D01*
Y-9811D01*
X499722D01*
Y-9844D01*
Y-9876D01*
X499754D01*
Y-9908D01*
X499786D01*
Y-9940D01*
X499819D01*
Y-9973D01*
Y-10005D01*
X499851D01*
Y-10037D01*
X499883D01*
Y-10069D01*
X499915D01*
Y-10102D01*
X499948D01*
Y-10134D01*
X499980D01*
Y-10166D01*
X500012D01*
Y-10199D01*
X500044D01*
Y-10231D01*
X500077D01*
Y-10263D01*
X500109D01*
Y-10295D01*
X500174D01*
Y-10328D01*
X500206D01*
Y-10360D01*
X500238D01*
Y-10392D01*
X500303D01*
Y-10424D01*
X500335D01*
Y-10457D01*
X500399D01*
Y-10489D01*
X500464D01*
Y-10521D01*
X500528D01*
Y-10554D01*
X500593D01*
Y-10586D01*
X500657D01*
Y-10618D01*
X500754D01*
Y-10650D01*
X500819D01*
Y-10683D01*
X500948D01*
Y-10715D01*
X501109D01*
Y-10747D01*
X501399D01*
Y-10779D01*
X508078D01*
Y-10812D01*
X508239D01*
Y-10844D01*
X508336D01*
Y-10876D01*
X508432D01*
Y-10908D01*
X508529D01*
Y-10941D01*
X508626D01*
Y-10973D01*
X508691D01*
Y-11005D01*
X508755D01*
Y-11037D01*
X508787D01*
Y-11070D01*
X508852D01*
Y-11102D01*
X508916D01*
Y-11134D01*
X508949D01*
Y-11167D01*
X509013D01*
Y-11199D01*
X509046D01*
Y-11231D01*
X509078D01*
Y-11263D01*
X509110D01*
Y-11295D01*
X509174D01*
Y-11328D01*
X509207D01*
Y-11360D01*
X509239D01*
Y-11392D01*
X509271D01*
Y-11425D01*
X509304D01*
Y-11457D01*
X509336D01*
Y-11489D01*
Y-11521D01*
X509368D01*
Y-11554D01*
X509400D01*
Y-11586D01*
X509433D01*
Y-11618D01*
X509465D01*
Y-11650D01*
Y-11683D01*
X509497D01*
Y-11715D01*
X509529D01*
Y-11747D01*
Y-11779D01*
X509562D01*
Y-11812D01*
X509594D01*
Y-11844D01*
Y-11876D01*
X509626D01*
Y-11908D01*
Y-11941D01*
X509658D01*
Y-11973D01*
Y-12005D01*
X509691D01*
Y-12037D01*
Y-12070D01*
X509723D01*
Y-12102D01*
Y-12134D01*
Y-12167D01*
X509755D01*
Y-12199D01*
Y-12231D01*
Y-12263D01*
X509788D01*
Y-12296D01*
Y-12328D01*
Y-12360D01*
X509820D01*
Y-12392D01*
Y-12425D01*
Y-12457D01*
Y-12489D01*
Y-12521D01*
Y-12554D01*
X509852D01*
Y-12586D01*
Y-12618D01*
Y-12651D01*
Y-12683D01*
Y-12715D01*
Y-12747D01*
Y-12780D01*
Y-12812D01*
Y-12844D01*
X509884D01*
Y-12876D01*
Y-12909D01*
X509852D01*
Y-12941D01*
Y-12973D01*
Y-13005D01*
Y-13038D01*
Y-13070D01*
Y-13102D01*
Y-13134D01*
Y-13167D01*
Y-13199D01*
Y-13231D01*
X509820D01*
Y-13263D01*
Y-13296D01*
Y-13328D01*
Y-13360D01*
Y-13393D01*
X509788D01*
Y-13425D01*
Y-13457D01*
Y-13489D01*
X509755D01*
Y-13522D01*
Y-13554D01*
Y-13586D01*
X509723D01*
Y-13618D01*
Y-13651D01*
Y-13683D01*
X509691D01*
Y-13715D01*
Y-13747D01*
Y-13780D01*
X509658D01*
Y-13812D01*
Y-13844D01*
X509626D01*
Y-13876D01*
Y-13909D01*
X509594D01*
Y-13941D01*
Y-13973D01*
X509562D01*
Y-14006D01*
X509529D01*
Y-14038D01*
Y-14070D01*
X509497D01*
Y-14102D01*
X509465D01*
Y-14134D01*
Y-14167D01*
X509433D01*
Y-14199D01*
X509400D01*
Y-14231D01*
X509368D01*
Y-14264D01*
Y-14296D01*
X509336D01*
Y-14328D01*
X509304D01*
Y-14360D01*
X509271D01*
Y-14393D01*
X509239D01*
Y-14425D01*
X509207D01*
Y-14457D01*
X509174D01*
Y-14489D01*
X509142D01*
Y-14522D01*
X509110D01*
Y-14554D01*
X509078D01*
Y-14586D01*
X509046D01*
Y-14618D01*
X508981D01*
Y-14651D01*
X508949D01*
Y-14683D01*
X508916D01*
Y-14715D01*
X508852D01*
Y-14748D01*
X508820D01*
Y-14780D01*
X508755D01*
Y-14812D01*
X508691D01*
Y-14844D01*
X508626D01*
Y-14877D01*
X508562D01*
Y-14909D01*
X508465D01*
Y-14941D01*
X508336D01*
Y-14973D01*
X485107D01*
Y-15006D01*
X485043D01*
Y-15038D01*
X485010D01*
Y-15070D01*
X484978D01*
Y-15102D01*
X484946D01*
Y-15135D01*
Y-15167D01*
X484914D01*
Y-15199D01*
Y-15231D01*
Y-15264D01*
Y-15296D01*
Y-15328D01*
Y-15360D01*
Y-15393D01*
Y-15425D01*
Y-15457D01*
Y-15489D01*
Y-15522D01*
Y-15554D01*
Y-15586D01*
Y-15619D01*
Y-15651D01*
Y-15683D01*
Y-15715D01*
Y-15748D01*
Y-15780D01*
Y-15812D01*
Y-15844D01*
Y-15877D01*
Y-15909D01*
Y-15941D01*
Y-15973D01*
Y-16006D01*
Y-16038D01*
Y-16070D01*
Y-16103D01*
Y-16135D01*
Y-16167D01*
Y-16199D01*
Y-16232D01*
Y-16264D01*
Y-16296D01*
Y-16328D01*
Y-16361D01*
Y-16393D01*
Y-16425D01*
Y-16457D01*
Y-16490D01*
Y-16522D01*
Y-16554D01*
Y-16586D01*
Y-16619D01*
Y-16651D01*
Y-16683D01*
Y-16715D01*
Y-16748D01*
Y-16780D01*
Y-16812D01*
Y-16845D01*
Y-16877D01*
Y-16909D01*
Y-16941D01*
Y-16974D01*
Y-17006D01*
Y-17038D01*
Y-17070D01*
Y-17103D01*
Y-17135D01*
Y-17167D01*
Y-17199D01*
Y-17232D01*
Y-17264D01*
Y-17296D01*
Y-17328D01*
Y-17361D01*
Y-17393D01*
Y-17425D01*
Y-17458D01*
Y-17490D01*
Y-17522D01*
Y-17554D01*
Y-17586D01*
Y-17619D01*
Y-17651D01*
Y-17683D01*
Y-17716D01*
Y-17748D01*
Y-17780D01*
Y-17812D01*
Y-17845D01*
Y-17877D01*
Y-17909D01*
Y-17941D01*
Y-17974D01*
Y-18006D01*
Y-18038D01*
Y-18070D01*
Y-18103D01*
Y-18135D01*
Y-18167D01*
Y-18200D01*
Y-18232D01*
Y-18264D01*
Y-18296D01*
Y-18329D01*
Y-18361D01*
X484881D01*
Y-18393D01*
Y-18425D01*
X484849D01*
Y-18458D01*
Y-18490D01*
X484817D01*
Y-18522D01*
X484752D01*
Y-18554D01*
X484688D01*
Y-18587D01*
X478526D01*
Y-18554D01*
X478429D01*
Y-18522D01*
X478397D01*
Y-18490D01*
X478365D01*
Y-18458D01*
X478332D01*
Y-18425D01*
Y-18393D01*
X478300D01*
Y-18361D01*
Y-18329D01*
Y-18296D01*
Y-18264D01*
Y-18232D01*
Y-18200D01*
Y-18167D01*
Y-18135D01*
Y-18103D01*
Y-18070D01*
Y-18038D01*
Y-18006D01*
Y-17974D01*
Y-17941D01*
Y-17909D01*
Y-17877D01*
Y-17845D01*
Y-17812D01*
Y-17780D01*
Y-17748D01*
Y-17716D01*
Y-17683D01*
Y-17651D01*
Y-17619D01*
Y-17586D01*
Y-17554D01*
Y-17522D01*
Y-17490D01*
Y-17458D01*
Y-17425D01*
Y-17393D01*
Y-17361D01*
Y-17328D01*
Y-17296D01*
Y-17264D01*
Y-17232D01*
Y-17199D01*
Y-17167D01*
Y-17135D01*
Y-17103D01*
Y-17070D01*
Y-17038D01*
Y-17006D01*
Y-16974D01*
Y-16941D01*
Y-16909D01*
Y-16877D01*
Y-16845D01*
Y-16812D01*
Y-16780D01*
Y-16748D01*
Y-16715D01*
Y-16683D01*
Y-16651D01*
Y-16619D01*
Y-16586D01*
Y-16554D01*
Y-16522D01*
Y-16490D01*
Y-16457D01*
Y-16425D01*
X478268D01*
Y-16393D01*
Y-16361D01*
Y-16328D01*
X478235D01*
Y-16296D01*
Y-16264D01*
X478203D01*
Y-16232D01*
X478139D01*
Y-16199D01*
X478042D01*
Y-16167D01*
X477945D01*
Y-16199D01*
X477848D01*
Y-16232D01*
X477816D01*
Y-16264D01*
X477784D01*
Y-16296D01*
X477752D01*
Y-16328D01*
X477719D01*
Y-16361D01*
Y-16393D01*
Y-16425D01*
Y-16457D01*
X477687D01*
Y-16490D01*
Y-16522D01*
Y-16554D01*
Y-16586D01*
Y-16619D01*
Y-16651D01*
Y-16683D01*
Y-16715D01*
Y-16748D01*
Y-16780D01*
Y-16812D01*
Y-16845D01*
Y-16877D01*
Y-16909D01*
Y-16941D01*
Y-16974D01*
Y-17006D01*
Y-17038D01*
Y-17070D01*
Y-17103D01*
Y-17135D01*
Y-17167D01*
Y-17199D01*
Y-17232D01*
Y-17264D01*
Y-17296D01*
Y-17328D01*
Y-17361D01*
Y-17393D01*
Y-17425D01*
Y-17458D01*
Y-17490D01*
Y-17522D01*
Y-17554D01*
Y-17586D01*
Y-17619D01*
Y-17651D01*
Y-17683D01*
Y-17716D01*
Y-17748D01*
Y-17780D01*
Y-17812D01*
Y-17845D01*
Y-17877D01*
Y-17909D01*
Y-17941D01*
Y-17974D01*
Y-18006D01*
Y-18038D01*
Y-18070D01*
Y-18103D01*
Y-18135D01*
Y-18167D01*
Y-18200D01*
Y-18232D01*
Y-18264D01*
Y-18296D01*
Y-18329D01*
Y-18361D01*
Y-18393D01*
Y-18425D01*
X477655D01*
Y-18458D01*
X477623D01*
Y-18490D01*
X477590D01*
Y-18522D01*
X477558D01*
Y-18554D01*
X477461D01*
Y-18587D01*
X474299D01*
Y-18554D01*
X474235D01*
Y-18522D01*
X474170D01*
Y-18490D01*
X474138D01*
Y-18458D01*
Y-18425D01*
X474106D01*
Y-18393D01*
Y-18361D01*
Y-18329D01*
X474074D01*
Y-18296D01*
Y-18264D01*
Y-18232D01*
Y-18200D01*
Y-18167D01*
Y-18135D01*
Y-18103D01*
Y-18070D01*
Y-18038D01*
Y-18006D01*
Y-17974D01*
Y-17941D01*
Y-17909D01*
Y-17877D01*
Y-17845D01*
Y-17812D01*
Y-17780D01*
Y-17748D01*
Y-17716D01*
Y-17683D01*
Y-17651D01*
Y-17619D01*
Y-17586D01*
Y-17554D01*
Y-17522D01*
Y-17490D01*
Y-17458D01*
Y-17425D01*
Y-17393D01*
Y-17361D01*
Y-17328D01*
Y-17296D01*
Y-17264D01*
Y-17232D01*
Y-17199D01*
Y-17167D01*
Y-17135D01*
Y-17103D01*
Y-17070D01*
Y-17038D01*
Y-17006D01*
Y-16974D01*
Y-16941D01*
Y-16909D01*
Y-16877D01*
Y-16845D01*
Y-16812D01*
Y-16780D01*
Y-16748D01*
Y-16715D01*
Y-16683D01*
Y-16651D01*
Y-16619D01*
Y-16586D01*
Y-16554D01*
Y-16522D01*
Y-16490D01*
Y-16457D01*
Y-16425D01*
Y-16393D01*
Y-16361D01*
Y-16328D01*
Y-16296D01*
Y-16264D01*
Y-16232D01*
Y-16199D01*
Y-16167D01*
Y-16135D01*
Y-16103D01*
Y-16070D01*
Y-16038D01*
Y-16006D01*
Y-15973D01*
Y-15941D01*
Y-15909D01*
Y-15877D01*
Y-15844D01*
Y-15812D01*
Y-15780D01*
Y-15748D01*
Y-15715D01*
X474106D01*
Y-15683D01*
X474074D01*
Y-15651D01*
Y-15619D01*
Y-15586D01*
Y-15554D01*
Y-15522D01*
Y-15489D01*
Y-15457D01*
Y-15425D01*
Y-15393D01*
X474041D01*
Y-15360D01*
Y-15328D01*
X474009D01*
Y-15296D01*
Y-15264D01*
X473977D01*
Y-15231D01*
Y-15199D01*
X473945D01*
Y-15167D01*
X473912D01*
Y-15135D01*
X473880D01*
Y-15102D01*
X473848D01*
Y-15070D01*
X473783D01*
Y-15038D01*
X473719D01*
Y-15006D01*
X473622D01*
Y-14973D01*
X473364D01*
Y-15006D01*
X473267D01*
Y-15038D01*
X473203D01*
Y-15070D01*
X473138D01*
Y-15102D01*
X473106D01*
Y-15135D01*
X473074D01*
Y-15167D01*
X473041D01*
Y-15199D01*
X473009D01*
Y-15231D01*
X472977D01*
Y-15264D01*
Y-15296D01*
X472944D01*
Y-15328D01*
Y-15360D01*
X472912D01*
Y-15393D01*
Y-15425D01*
Y-15457D01*
Y-15489D01*
Y-15522D01*
Y-15554D01*
X472880D01*
Y-15586D01*
X472912D01*
Y-15619D01*
Y-15651D01*
X472880D01*
Y-15683D01*
X472912D01*
Y-15715D01*
Y-15748D01*
Y-15780D01*
Y-15812D01*
Y-15844D01*
Y-15877D01*
Y-15909D01*
Y-15941D01*
Y-15973D01*
Y-16006D01*
Y-16038D01*
Y-16070D01*
Y-16103D01*
Y-16135D01*
Y-16167D01*
Y-16199D01*
Y-16232D01*
Y-16264D01*
Y-16296D01*
Y-16328D01*
Y-16361D01*
Y-16393D01*
Y-16425D01*
Y-16457D01*
Y-16490D01*
Y-16522D01*
Y-16554D01*
Y-16586D01*
Y-16619D01*
Y-16651D01*
Y-16683D01*
Y-16715D01*
Y-16748D01*
Y-16780D01*
Y-16812D01*
Y-16845D01*
Y-16877D01*
Y-16909D01*
Y-16941D01*
Y-16974D01*
Y-17006D01*
Y-17038D01*
Y-17070D01*
X472880D01*
Y-17103D01*
Y-17135D01*
Y-17167D01*
Y-17199D01*
X472848D01*
Y-17232D01*
X472816D01*
Y-17264D01*
X472783D01*
Y-17296D01*
X472751D01*
Y-17328D01*
X472654D01*
Y-17361D01*
X470718D01*
Y-17328D01*
X470622D01*
Y-17296D01*
X470589D01*
Y-17264D01*
X470557D01*
Y-17232D01*
X470525D01*
Y-17199D01*
X470493D01*
Y-17167D01*
Y-17135D01*
Y-17103D01*
X470460D01*
Y-17070D01*
Y-17038D01*
Y-17006D01*
Y-16974D01*
Y-16941D01*
Y-16909D01*
Y-16877D01*
Y-16845D01*
Y-16812D01*
Y-16780D01*
Y-16748D01*
Y-16715D01*
Y-16683D01*
Y-16651D01*
Y-16619D01*
Y-16586D01*
Y-16554D01*
Y-16522D01*
Y-16490D01*
Y-16457D01*
Y-16425D01*
Y-16393D01*
Y-16361D01*
Y-16328D01*
Y-16296D01*
Y-16264D01*
Y-16232D01*
Y-16199D01*
Y-16167D01*
Y-16135D01*
Y-16103D01*
Y-16070D01*
Y-16038D01*
Y-16006D01*
Y-15973D01*
Y-15941D01*
Y-15909D01*
Y-15877D01*
Y-15844D01*
Y-15812D01*
Y-15780D01*
Y-15748D01*
Y-15715D01*
Y-15683D01*
Y-15651D01*
Y-15619D01*
Y-15586D01*
Y-15554D01*
Y-15522D01*
Y-15489D01*
Y-15457D01*
X470493D01*
Y-15425D01*
Y-15393D01*
X470460D01*
Y-15360D01*
X470493D01*
Y-15328D01*
X470460D01*
Y-15296D01*
Y-15264D01*
Y-15231D01*
Y-15199D01*
Y-15167D01*
Y-15135D01*
X470428D01*
Y-15102D01*
Y-15070D01*
X470396D01*
Y-15038D01*
X470331D01*
Y-15006D01*
X470267D01*
Y-14973D01*
X465266D01*
Y-15006D01*
X465202D01*
Y-15038D01*
X465169D01*
Y-15070D01*
X465137D01*
Y-15102D01*
X465105D01*
Y-15135D01*
Y-15167D01*
X465073D01*
Y-15199D01*
Y-15231D01*
Y-15264D01*
Y-15296D01*
Y-15328D01*
Y-15360D01*
Y-15393D01*
Y-15425D01*
Y-15457D01*
Y-15489D01*
Y-15522D01*
Y-15554D01*
Y-15586D01*
Y-15619D01*
Y-15651D01*
Y-15683D01*
Y-15715D01*
Y-15748D01*
Y-15780D01*
Y-15812D01*
Y-15844D01*
Y-15877D01*
Y-15909D01*
Y-15941D01*
Y-15973D01*
Y-16006D01*
Y-16038D01*
Y-16070D01*
Y-16103D01*
Y-16135D01*
Y-16167D01*
Y-16199D01*
Y-16232D01*
Y-16264D01*
Y-16296D01*
Y-16328D01*
Y-16361D01*
Y-16393D01*
Y-16425D01*
Y-16457D01*
Y-16490D01*
Y-16522D01*
Y-16554D01*
Y-16586D01*
Y-16619D01*
Y-16651D01*
Y-16683D01*
Y-16715D01*
Y-16748D01*
Y-16780D01*
Y-16812D01*
Y-16845D01*
Y-16877D01*
Y-16909D01*
Y-16941D01*
Y-16974D01*
Y-17006D01*
Y-17038D01*
Y-17070D01*
Y-17103D01*
Y-17135D01*
Y-17167D01*
Y-17199D01*
Y-17232D01*
Y-17264D01*
Y-17296D01*
Y-17328D01*
Y-17361D01*
Y-17393D01*
Y-17425D01*
Y-17458D01*
Y-17490D01*
Y-17522D01*
Y-17554D01*
Y-17586D01*
Y-17619D01*
Y-17651D01*
Y-17683D01*
Y-17716D01*
Y-17748D01*
Y-17780D01*
Y-17812D01*
Y-17845D01*
Y-17877D01*
Y-17909D01*
Y-17941D01*
Y-17974D01*
X460266D01*
Y-17941D01*
Y-17909D01*
Y-17877D01*
Y-17845D01*
Y-17812D01*
Y-17780D01*
Y-17748D01*
Y-17716D01*
Y-17683D01*
Y-17651D01*
Y-17619D01*
Y-17586D01*
Y-17554D01*
Y-17522D01*
Y-17490D01*
Y-17458D01*
Y-17425D01*
Y-17393D01*
Y-17361D01*
Y-17328D01*
Y-17296D01*
Y-17264D01*
Y-17232D01*
Y-17199D01*
Y-17167D01*
Y-17135D01*
Y-17103D01*
Y-17070D01*
Y-17038D01*
Y-17006D01*
Y-16974D01*
Y-16941D01*
Y-16909D01*
Y-16877D01*
Y-16845D01*
Y-16812D01*
Y-16780D01*
Y-16748D01*
Y-16715D01*
Y-16683D01*
Y-16651D01*
Y-16619D01*
Y-16586D01*
Y-16554D01*
Y-16522D01*
Y-16490D01*
Y-16457D01*
Y-16425D01*
Y-16393D01*
Y-16361D01*
Y-16328D01*
Y-16296D01*
Y-16264D01*
Y-16232D01*
Y-16199D01*
Y-16167D01*
Y-16135D01*
Y-16103D01*
Y-16070D01*
Y-16038D01*
Y-16006D01*
Y-15973D01*
Y-15941D01*
Y-15909D01*
Y-15877D01*
Y-15844D01*
Y-15812D01*
Y-15780D01*
Y-15748D01*
Y-15715D01*
Y-15683D01*
Y-15651D01*
Y-15619D01*
Y-15586D01*
Y-15554D01*
Y-15522D01*
Y-15489D01*
Y-15457D01*
Y-15425D01*
Y-15393D01*
Y-15360D01*
Y-15328D01*
Y-15296D01*
Y-15264D01*
Y-15231D01*
Y-15199D01*
Y-15167D01*
Y-15135D01*
Y-15102D01*
Y-15070D01*
X463395D01*
Y-15038D01*
Y-15006D01*
Y-14973D01*
Y-14941D01*
Y-14909D01*
Y-14877D01*
Y-14844D01*
Y-14812D01*
Y-14780D01*
Y-14748D01*
Y-14715D01*
Y-14683D01*
Y-14651D01*
Y-14618D01*
Y-14586D01*
Y-14554D01*
Y-14522D01*
Y-14489D01*
Y-14457D01*
Y-14425D01*
Y-14393D01*
Y-14360D01*
Y-14328D01*
Y-14296D01*
Y-14264D01*
Y-14231D01*
Y-14199D01*
Y-14167D01*
Y-14134D01*
Y-14102D01*
Y-14070D01*
Y-14038D01*
Y-14006D01*
Y-13973D01*
Y-13941D01*
Y-13909D01*
Y-13876D01*
Y-13844D01*
Y-13812D01*
Y-13780D01*
Y-13747D01*
Y-13715D01*
Y-13683D01*
Y-13651D01*
Y-13618D01*
Y-13586D01*
Y-13554D01*
Y-13522D01*
Y-13489D01*
Y-13457D01*
Y-13425D01*
Y-13393D01*
Y-13360D01*
Y-13328D01*
Y-13296D01*
Y-13263D01*
Y-13231D01*
Y-13199D01*
Y-13167D01*
Y-13134D01*
Y-13102D01*
Y-13070D01*
Y-13038D01*
Y-13005D01*
Y-12973D01*
Y-12941D01*
Y-12909D01*
Y-12876D01*
Y-12844D01*
Y-12812D01*
Y-12780D01*
Y-12747D01*
Y-12715D01*
Y-12683D01*
Y-12651D01*
Y-12618D01*
Y-12586D01*
Y-12554D01*
Y-12521D01*
Y-12489D01*
Y-12457D01*
Y-12425D01*
Y-12392D01*
Y-12360D01*
Y-12328D01*
Y-12296D01*
Y-12263D01*
Y-12231D01*
Y-12199D01*
Y-12167D01*
Y-12134D01*
Y-12102D01*
Y-12070D01*
Y-12037D01*
Y-12005D01*
Y-11973D01*
Y-11941D01*
Y-11908D01*
Y-11876D01*
Y-11844D01*
Y-11812D01*
Y-11779D01*
Y-11747D01*
Y-11715D01*
Y-11683D01*
Y-11650D01*
Y-11618D01*
Y-11586D01*
Y-11554D01*
Y-11521D01*
X460266D01*
Y-11489D01*
Y-11457D01*
Y-11425D01*
Y-11392D01*
Y-11360D01*
Y-11328D01*
Y-11295D01*
Y-11263D01*
Y-11231D01*
Y-11199D01*
Y-11167D01*
Y-11134D01*
Y-11102D01*
Y-11070D01*
Y-11037D01*
Y-11005D01*
Y-10973D01*
Y-10941D01*
Y-10908D01*
Y-10876D01*
Y-10844D01*
Y-10812D01*
Y-10779D01*
Y-10747D01*
Y-10715D01*
X463395D01*
Y-10683D01*
Y-10650D01*
Y-10618D01*
Y-10586D01*
Y-10554D01*
Y-10521D01*
Y-10489D01*
Y-10457D01*
Y-10424D01*
Y-10392D01*
Y-10360D01*
Y-10328D01*
Y-10295D01*
Y-10263D01*
Y-10231D01*
Y-10199D01*
Y-10166D01*
Y-10134D01*
Y-10102D01*
Y-10069D01*
Y-10037D01*
Y-10005D01*
Y-9973D01*
Y-9940D01*
Y-9908D01*
Y-9876D01*
Y-9844D01*
Y-9811D01*
Y-9779D01*
Y-9747D01*
Y-9715D01*
Y-9682D01*
Y-9650D01*
Y-9618D01*
Y-9586D01*
Y-9553D01*
Y-9521D01*
Y-9489D01*
Y-9457D01*
Y-9424D01*
Y-9392D01*
Y-9360D01*
Y-9328D01*
Y-9295D01*
Y-9263D01*
Y-9231D01*
Y-9199D01*
Y-9166D01*
Y-9134D01*
Y-9102D01*
Y-9069D01*
Y-9037D01*
Y-9005D01*
Y-8973D01*
Y-8940D01*
Y-8908D01*
Y-8876D01*
Y-8844D01*
Y-8811D01*
Y-8779D01*
Y-8747D01*
Y-8715D01*
Y-8682D01*
Y-8650D01*
Y-8618D01*
Y-8585D01*
Y-8553D01*
Y-8521D01*
Y-8489D01*
Y-8456D01*
Y-8424D01*
Y-8392D01*
Y-8360D01*
Y-8327D01*
Y-8295D01*
Y-8263D01*
Y-8231D01*
Y-8198D01*
Y-8166D01*
Y-8134D01*
Y-8102D01*
Y-8069D01*
Y-8037D01*
Y-8005D01*
Y-7972D01*
Y-7940D01*
Y-7908D01*
Y-7876D01*
Y-7843D01*
Y-7811D01*
Y-7779D01*
Y-7747D01*
Y-7714D01*
Y-7682D01*
Y-7650D01*
Y-7618D01*
Y-7585D01*
Y-7553D01*
Y-7521D01*
Y-7489D01*
Y-7456D01*
Y-7424D01*
Y-7392D01*
Y-7360D01*
Y-7327D01*
Y-7295D01*
Y-7263D01*
Y-7231D01*
Y-7198D01*
Y-7166D01*
X460298D01*
Y-7134D01*
X460266D01*
Y-7102D01*
Y-7069D01*
Y-7037D01*
Y-7005D01*
Y-6972D01*
Y-6940D01*
Y-6908D01*
Y-6876D01*
Y-6843D01*
Y-6811D01*
Y-6779D01*
Y-6747D01*
Y-6714D01*
Y-6682D01*
Y-6650D01*
Y-6617D01*
Y-6585D01*
Y-6553D01*
Y-6521D01*
Y-6488D01*
Y-6456D01*
Y-6424D01*
Y-6392D01*
Y-6359D01*
X463395D01*
Y-6327D01*
Y-6295D01*
Y-6263D01*
Y-6230D01*
Y-6198D01*
Y-6166D01*
Y-6134D01*
Y-6101D01*
Y-6069D01*
Y-6037D01*
Y-6005D01*
Y-5972D01*
Y-5940D01*
Y-5908D01*
Y-5875D01*
Y-5843D01*
Y-5811D01*
Y-5779D01*
Y-5746D01*
Y-5714D01*
Y-5682D01*
Y-5650D01*
Y-5617D01*
Y-5585D01*
Y-5553D01*
Y-5521D01*
Y-5488D01*
Y-5456D01*
Y-5424D01*
Y-5392D01*
Y-5359D01*
Y-5327D01*
Y-5295D01*
Y-5263D01*
Y-5230D01*
Y-5198D01*
Y-5166D01*
Y-5133D01*
Y-5101D01*
Y-5069D01*
Y-5037D01*
Y-5004D01*
Y-4972D01*
Y-4940D01*
Y-4908D01*
Y-4875D01*
Y-4843D01*
Y-4811D01*
Y-4779D01*
Y-4746D01*
Y-4714D01*
Y-4682D01*
Y-4650D01*
Y-4617D01*
Y-4585D01*
Y-4553D01*
Y-4521D01*
Y-4488D01*
Y-4456D01*
Y-4424D01*
Y-4391D01*
Y-4359D01*
Y-4327D01*
Y-4295D01*
Y-4262D01*
Y-4230D01*
Y-4198D01*
Y-4166D01*
Y-4133D01*
Y-4101D01*
Y-4069D01*
Y-4037D01*
Y-4004D01*
Y-3972D01*
Y-3940D01*
Y-3907D01*
Y-3875D01*
Y-3843D01*
Y-3811D01*
Y-3779D01*
Y-3746D01*
Y-3714D01*
Y-3682D01*
Y-3650D01*
Y-3617D01*
Y-3585D01*
Y-3553D01*
Y-3520D01*
Y-3488D01*
Y-3456D01*
Y-3424D01*
Y-3391D01*
Y-3359D01*
Y-3327D01*
Y-3295D01*
Y-3262D01*
Y-3230D01*
Y-3198D01*
Y-3165D01*
Y-3133D01*
Y-3101D01*
Y-3069D01*
Y-3036D01*
Y-3004D01*
Y-2972D01*
Y-2940D01*
Y-2907D01*
Y-2875D01*
Y-2843D01*
Y-2811D01*
Y-2778D01*
X460266D01*
Y-2746D01*
Y-2714D01*
Y-2682D01*
Y-2649D01*
Y-2617D01*
Y-2585D01*
Y-2553D01*
Y-2520D01*
Y-2488D01*
Y-2456D01*
Y-2424D01*
Y-2391D01*
Y-2359D01*
Y-2327D01*
Y-2294D01*
Y-2262D01*
Y-2230D01*
Y-2198D01*
Y-2165D01*
Y-2133D01*
Y-2101D01*
Y-2069D01*
Y-2036D01*
Y-2004D01*
X460298D01*
Y-1972D01*
X463395D01*
Y-1940D01*
Y-1907D01*
Y-1875D01*
Y-1843D01*
Y-1811D01*
Y-1778D01*
Y-1746D01*
Y-1714D01*
Y-1681D01*
Y-1649D01*
Y-1617D01*
Y-1585D01*
Y-1552D01*
Y-1520D01*
Y-1488D01*
Y-1456D01*
Y-1423D01*
Y-1391D01*
Y-1359D01*
Y-1327D01*
Y-1294D01*
Y-1262D01*
Y-1230D01*
Y-1198D01*
Y-1165D01*
Y-1133D01*
Y-1101D01*
Y-1068D01*
Y-1036D01*
Y-1004D01*
Y-972D01*
Y-939D01*
Y-907D01*
Y-875D01*
Y-843D01*
Y-810D01*
Y-778D01*
Y-746D01*
Y-714D01*
Y-681D01*
Y-649D01*
Y-617D01*
Y-585D01*
Y-552D01*
Y-520D01*
Y-488D01*
Y-455D01*
Y-423D01*
Y-391D01*
Y-359D01*
Y-326D01*
Y-294D01*
Y-262D01*
Y-230D01*
Y-197D01*
Y-165D01*
Y-133D01*
Y-101D01*
Y-68D01*
Y-36D01*
Y-4D01*
Y28D01*
Y61D01*
Y93D01*
Y125D01*
Y157D01*
Y190D01*
Y222D01*
Y254D01*
Y286D01*
Y319D01*
Y351D01*
Y383D01*
Y416D01*
Y448D01*
Y480D01*
Y512D01*
Y545D01*
Y577D01*
Y609D01*
Y641D01*
Y674D01*
Y706D01*
Y738D01*
Y770D01*
Y803D01*
Y835D01*
Y867D01*
Y900D01*
Y932D01*
Y964D01*
Y996D01*
Y1029D01*
Y1061D01*
Y1093D01*
Y1125D01*
Y1158D01*
Y1190D01*
Y1222D01*
Y1254D01*
Y1287D01*
Y1319D01*
Y1351D01*
Y1383D01*
Y1416D01*
Y1448D01*
Y1480D01*
Y1512D01*
Y1545D01*
Y1577D01*
X460266D01*
Y1609D01*
Y1641D01*
Y1674D01*
Y1706D01*
Y1738D01*
Y1770D01*
Y1803D01*
Y1835D01*
Y1867D01*
Y1900D01*
Y1932D01*
Y1964D01*
Y1996D01*
Y2029D01*
Y2061D01*
Y2093D01*
Y2125D01*
Y2158D01*
Y2190D01*
Y2222D01*
Y2254D01*
Y2287D01*
Y2319D01*
Y2351D01*
Y2383D01*
Y2416D01*
Y2448D01*
Y2480D01*
Y2513D01*
Y2545D01*
Y2577D01*
Y2609D01*
Y2642D01*
Y2674D01*
Y2706D01*
Y2738D01*
Y2771D01*
Y2803D01*
Y2835D01*
Y2867D01*
Y2900D01*
Y2932D01*
Y2964D01*
Y2997D01*
Y3029D01*
Y3061D01*
Y3093D01*
Y3125D01*
Y3158D01*
Y3190D01*
Y3222D01*
Y3255D01*
Y3287D01*
Y3319D01*
Y3351D01*
Y3384D01*
Y3416D01*
Y3448D01*
Y3480D01*
Y3513D01*
Y3545D01*
Y3577D01*
Y3609D01*
Y3642D01*
Y3674D01*
Y3706D01*
Y3739D01*
Y3771D01*
Y3803D01*
Y3835D01*
Y3867D01*
Y3900D01*
Y3932D01*
Y3964D01*
Y3997D01*
Y4029D01*
Y4061D01*
Y4093D01*
Y4126D01*
Y4158D01*
Y4190D01*
Y4222D01*
Y4255D01*
Y4287D01*
Y4319D01*
Y4352D01*
Y4384D01*
Y4416D01*
Y4448D01*
Y4481D01*
Y4513D01*
Y4545D01*
Y4577D01*
Y4610D01*
Y4642D01*
Y4674D01*
Y4706D01*
Y4739D01*
Y4771D01*
Y4803D01*
Y4835D01*
Y4868D01*
Y4900D01*
Y4932D01*
Y4964D01*
Y4997D01*
Y5029D01*
Y5061D01*
Y5094D01*
Y5126D01*
Y5158D01*
Y5190D01*
Y5223D01*
Y5255D01*
Y5287D01*
Y5319D01*
Y5352D01*
Y5384D01*
Y5416D01*
Y5448D01*
Y5481D01*
Y5513D01*
Y5545D01*
Y5577D01*
Y5610D01*
Y5642D01*
Y5674D01*
Y5706D01*
Y5739D01*
Y5771D01*
Y5803D01*
Y5835D01*
Y5868D01*
Y5900D01*
Y5932D01*
Y5965D01*
Y5997D01*
Y6029D01*
Y6061D01*
Y6094D01*
Y6126D01*
Y6158D01*
Y6190D01*
Y6223D01*
Y6255D01*
Y6287D01*
Y6319D01*
Y6352D01*
Y6384D01*
Y6416D01*
Y6448D01*
Y6481D01*
Y6513D01*
Y6545D01*
Y6577D01*
Y6610D01*
Y6642D01*
Y6674D01*
Y6707D01*
Y6739D01*
Y6771D01*
Y6803D01*
Y6836D01*
Y6868D01*
Y6900D01*
Y6932D01*
Y6965D01*
Y6997D01*
Y7029D01*
Y7062D01*
Y7094D01*
Y7126D01*
Y7158D01*
Y7191D01*
Y7223D01*
Y7255D01*
Y7287D01*
Y7320D01*
Y7352D01*
Y7384D01*
Y7416D01*
Y7449D01*
Y7481D01*
Y7513D01*
Y7545D01*
Y7578D01*
Y7610D01*
Y7642D01*
Y7674D01*
Y7707D01*
Y7739D01*
Y7771D01*
Y7803D01*
Y7836D01*
Y7868D01*
Y7900D01*
Y7932D01*
Y7965D01*
Y7997D01*
Y8029D01*
Y8062D01*
Y8094D01*
Y8126D01*
Y8158D01*
Y8191D01*
Y8223D01*
Y8255D01*
Y8287D01*
Y8320D01*
Y8352D01*
Y8384D01*
Y8416D01*
Y8449D01*
Y8481D01*
Y8513D01*
Y8546D01*
Y8578D01*
Y8610D01*
Y8642D01*
Y8675D01*
Y8707D01*
Y8739D01*
Y8771D01*
Y8804D01*
Y8836D01*
Y8868D01*
Y8900D01*
Y8933D01*
Y8965D01*
Y8997D01*
Y9029D01*
Y9062D01*
Y9094D01*
Y9126D01*
Y9159D01*
Y9191D01*
Y9223D01*
Y9255D01*
Y9287D01*
Y9320D01*
Y9352D01*
Y9384D01*
Y9417D01*
Y9449D01*
Y9481D01*
Y9513D01*
Y9546D01*
Y9578D01*
Y9610D01*
Y9642D01*
Y9675D01*
Y9707D01*
Y9739D01*
Y9771D01*
Y9804D01*
Y9836D01*
Y9868D01*
Y9900D01*
Y9933D01*
Y9965D01*
Y9997D01*
Y10029D01*
Y10062D01*
Y10094D01*
Y10126D01*
Y10159D01*
Y10191D01*
Y10223D01*
Y10255D01*
Y10288D01*
Y10320D01*
Y10352D01*
Y10384D01*
Y10417D01*
Y10449D01*
Y10481D01*
Y10514D01*
Y10546D01*
Y10578D01*
Y10610D01*
Y10643D01*
Y10675D01*
Y10707D01*
Y10739D01*
Y10772D01*
Y10804D01*
Y10836D01*
Y10868D01*
Y10901D01*
Y10933D01*
Y10965D01*
Y10997D01*
Y11030D01*
Y11062D01*
Y11094D01*
Y11126D01*
Y11159D01*
Y11191D01*
Y11223D01*
Y11255D01*
Y11288D01*
Y11320D01*
Y11352D01*
Y11384D01*
Y11417D01*
Y11449D01*
Y11481D01*
Y11514D01*
Y11546D01*
Y11578D01*
Y11610D01*
Y11643D01*
Y11675D01*
Y11707D01*
Y11739D01*
Y11772D01*
Y11804D01*
Y11836D01*
Y11868D01*
Y11901D01*
Y11933D01*
Y11965D01*
Y11998D01*
Y12030D01*
Y12062D01*
Y12094D01*
Y12127D01*
Y12159D01*
Y12191D01*
Y12223D01*
Y12256D01*
Y12288D01*
Y12320D01*
Y12352D01*
Y12385D01*
Y12417D01*
Y12449D01*
Y12481D01*
Y12514D01*
Y12546D01*
Y12578D01*
Y12610D01*
Y12643D01*
Y12675D01*
Y12707D01*
Y12740D01*
Y12772D01*
Y12804D01*
Y12836D01*
Y12869D01*
Y12901D01*
Y12933D01*
Y12965D01*
Y12998D01*
Y13030D01*
Y13062D01*
Y13094D01*
Y13127D01*
Y13159D01*
Y13191D01*
Y13223D01*
Y13256D01*
Y13288D01*
Y13320D01*
Y13352D01*
Y13385D01*
Y13417D01*
Y13449D01*
Y13482D01*
Y13514D01*
Y13546D01*
Y13578D01*
Y13611D01*
Y13643D01*
Y13675D01*
Y13707D01*
Y13740D01*
Y13772D01*
Y13804D01*
Y13836D01*
Y13869D01*
Y13901D01*
Y13933D01*
Y13965D01*
Y13998D01*
Y14030D01*
Y14062D01*
Y14095D01*
Y14127D01*
Y14159D01*
Y14191D01*
Y14224D01*
Y14256D01*
Y14288D01*
Y14320D01*
Y14353D01*
Y14385D01*
Y14417D01*
Y14449D01*
X460298D01*
Y14482D01*
X501012D01*
Y14449D01*
D02*
G37*
G36*
X461750Y-7747D02*
X461911D01*
Y-7779D01*
X462008D01*
Y-7811D01*
X462105D01*
Y-7843D01*
X462169D01*
Y-7876D01*
X462234D01*
Y-7908D01*
X462266D01*
Y-7940D01*
X462330D01*
Y-7972D01*
X462363D01*
Y-8005D01*
X462395D01*
Y-8037D01*
X462427D01*
Y-8069D01*
X462460D01*
Y-8102D01*
X462492D01*
Y-8134D01*
X462524D01*
Y-8166D01*
X462556D01*
Y-8198D01*
X462589D01*
Y-8231D01*
Y-8263D01*
X462621D01*
Y-8295D01*
X462653D01*
Y-8327D01*
Y-8360D01*
X462685D01*
Y-8392D01*
Y-8424D01*
X462718D01*
Y-8456D01*
Y-8489D01*
X462750D01*
Y-8521D01*
Y-8553D01*
Y-8585D01*
X462782D01*
Y-8618D01*
Y-8650D01*
Y-8682D01*
Y-8715D01*
X462814D01*
Y-8747D01*
Y-8779D01*
Y-8811D01*
Y-8844D01*
Y-8876D01*
Y-8908D01*
Y-8940D01*
Y-8973D01*
Y-9005D01*
Y-9037D01*
Y-9069D01*
Y-9102D01*
Y-9134D01*
X462782D01*
Y-9166D01*
Y-9199D01*
Y-9231D01*
Y-9263D01*
X462750D01*
Y-9295D01*
Y-9328D01*
Y-9360D01*
X462718D01*
Y-9392D01*
Y-9424D01*
Y-9457D01*
X462685D01*
Y-9489D01*
Y-9521D01*
X462653D01*
Y-9553D01*
X462621D01*
Y-9586D01*
Y-9618D01*
X462589D01*
Y-9650D01*
X462556D01*
Y-9682D01*
Y-9715D01*
X462524D01*
Y-9747D01*
X462492D01*
Y-9779D01*
X462460D01*
Y-9811D01*
X462427D01*
Y-9844D01*
X462395D01*
Y-9876D01*
X462330D01*
Y-9908D01*
X462298D01*
Y-9940D01*
X462234D01*
Y-9973D01*
X462201D01*
Y-10005D01*
X462137D01*
Y-10037D01*
X462040D01*
Y-10069D01*
X461976D01*
Y-10102D01*
X461846D01*
Y-10134D01*
X461363D01*
Y-10102D01*
X461266D01*
Y-10069D01*
X461169D01*
Y-10037D01*
X461072D01*
Y-10005D01*
X461040D01*
Y-9973D01*
X460975D01*
Y-9940D01*
X460911D01*
Y-9908D01*
X460879D01*
Y-9876D01*
X460846D01*
Y-9844D01*
X460782D01*
Y-9811D01*
X460750D01*
Y-9779D01*
X460717D01*
Y-9747D01*
X460685D01*
Y-9715D01*
Y-9682D01*
X460653D01*
Y-9650D01*
X460620D01*
Y-9618D01*
X460588D01*
Y-9586D01*
Y-9553D01*
X460556D01*
Y-9521D01*
Y-9489D01*
X460524D01*
Y-9457D01*
Y-9424D01*
X460492D01*
Y-9392D01*
Y-9360D01*
X460459D01*
Y-9328D01*
Y-9295D01*
Y-9263D01*
X460427D01*
Y-9231D01*
Y-9199D01*
Y-9166D01*
Y-9134D01*
Y-9102D01*
X460395D01*
Y-9069D01*
Y-9037D01*
Y-9005D01*
Y-8973D01*
Y-8940D01*
Y-8908D01*
Y-8876D01*
Y-8844D01*
Y-8811D01*
Y-8779D01*
X460427D01*
Y-8747D01*
Y-8715D01*
Y-8682D01*
Y-8650D01*
Y-8618D01*
X460459D01*
Y-8585D01*
Y-8553D01*
Y-8521D01*
X460492D01*
Y-8489D01*
Y-8456D01*
Y-8424D01*
X460524D01*
Y-8392D01*
Y-8360D01*
X460556D01*
Y-8327D01*
Y-8295D01*
X460588D01*
Y-8263D01*
X460620D01*
Y-8231D01*
Y-8198D01*
X460653D01*
Y-8166D01*
X460685D01*
Y-8134D01*
X460717D01*
Y-8102D01*
X460750D01*
Y-8069D01*
X460782D01*
Y-8037D01*
X460814D01*
Y-8005D01*
X460846D01*
Y-7972D01*
X460879D01*
Y-7940D01*
X460943D01*
Y-7908D01*
X461008D01*
Y-7876D01*
X461040D01*
Y-7843D01*
X461104D01*
Y-7811D01*
X461201D01*
Y-7779D01*
X461298D01*
Y-7747D01*
X461459D01*
Y-7714D01*
X461750D01*
Y-7747D01*
D02*
G37*
G36*
X88189Y5512D02*
X114242D01*
Y-11593D01*
X109126D01*
Y-12129D01*
X108958D01*
Y-13897D01*
X106432D01*
Y-6497D01*
Y1158D01*
X104986D01*
X104721Y1336D01*
X104331Y1413D01*
X96850D01*
X96460Y1336D01*
X96195Y1158D01*
X68563D01*
Y20079D01*
X88189D01*
Y5512D01*
D02*
G37*
G36*
X104331Y-4380D02*
X105207D01*
Y-5379D01*
X105243D01*
Y-13897D01*
X102643D01*
Y-5118D01*
X96850D01*
Y394D01*
X104331D01*
Y-4380D01*
D02*
G37*
G36*
X461879Y-12134D02*
X462008D01*
Y-12167D01*
X462072D01*
Y-12199D01*
X462137D01*
Y-12231D01*
X462201D01*
Y-12263D01*
X462266D01*
Y-12296D01*
X462298D01*
Y-12328D01*
X462363D01*
Y-12360D01*
X462395D01*
Y-12392D01*
X462427D01*
Y-12425D01*
X462460D01*
Y-12457D01*
X462492D01*
Y-12489D01*
X462524D01*
Y-12521D01*
X462556D01*
Y-12554D01*
X462589D01*
Y-12586D01*
Y-12618D01*
X462621D01*
Y-12651D01*
X462653D01*
Y-12683D01*
Y-12715D01*
X462685D01*
Y-12747D01*
Y-12780D01*
X462718D01*
Y-12812D01*
Y-12844D01*
X462750D01*
Y-12876D01*
Y-12909D01*
Y-12941D01*
X462782D01*
Y-12973D01*
Y-13005D01*
Y-13038D01*
Y-13070D01*
Y-13102D01*
X462814D01*
Y-13134D01*
Y-13167D01*
Y-13199D01*
Y-13231D01*
Y-13263D01*
Y-13296D01*
Y-13328D01*
Y-13360D01*
Y-13393D01*
Y-13425D01*
Y-13457D01*
Y-13489D01*
X462782D01*
Y-13522D01*
Y-13554D01*
Y-13586D01*
Y-13618D01*
Y-13651D01*
X462750D01*
Y-13683D01*
Y-13715D01*
Y-13747D01*
X462718D01*
Y-13780D01*
Y-13812D01*
X462685D01*
Y-13844D01*
Y-13876D01*
X462653D01*
Y-13909D01*
Y-13941D01*
X462621D01*
Y-13973D01*
X462589D01*
Y-14006D01*
Y-14038D01*
X462556D01*
Y-14070D01*
X462524D01*
Y-14102D01*
X462492D01*
Y-14134D01*
X462460D01*
Y-14167D01*
X462427D01*
Y-14199D01*
X462395D01*
Y-14231D01*
X462363D01*
Y-14264D01*
X462298D01*
Y-14296D01*
X462266D01*
Y-14328D01*
X462201D01*
Y-14360D01*
X462137D01*
Y-14393D01*
X462072D01*
Y-14425D01*
X461976D01*
Y-14457D01*
X461879D01*
Y-14489D01*
X461330D01*
Y-14457D01*
X461234D01*
Y-14425D01*
X461137D01*
Y-14393D01*
X461072D01*
Y-14360D01*
X461008D01*
Y-14328D01*
X460943D01*
Y-14296D01*
X460911D01*
Y-14264D01*
X460879D01*
Y-14231D01*
X460814D01*
Y-14199D01*
X460782D01*
Y-14167D01*
X460750D01*
Y-14134D01*
X460717D01*
Y-14102D01*
X460685D01*
Y-14070D01*
X460653D01*
Y-14038D01*
Y-14006D01*
X460620D01*
Y-13973D01*
X460588D01*
Y-13941D01*
Y-13909D01*
X460556D01*
Y-13876D01*
Y-13844D01*
X460524D01*
Y-13812D01*
Y-13780D01*
X460492D01*
Y-13747D01*
Y-13715D01*
X460459D01*
Y-13683D01*
Y-13651D01*
Y-13618D01*
X460427D01*
Y-13586D01*
Y-13554D01*
Y-13522D01*
Y-13489D01*
Y-13457D01*
X460395D01*
Y-13425D01*
Y-13393D01*
Y-13360D01*
Y-13328D01*
Y-13296D01*
Y-13263D01*
Y-13231D01*
Y-13199D01*
Y-13167D01*
Y-13134D01*
X460427D01*
Y-13102D01*
Y-13070D01*
Y-13038D01*
Y-13005D01*
Y-12973D01*
X460459D01*
Y-12941D01*
Y-12909D01*
Y-12876D01*
X460492D01*
Y-12844D01*
Y-12812D01*
X460524D01*
Y-12780D01*
Y-12747D01*
X460556D01*
Y-12715D01*
Y-12683D01*
X460588D01*
Y-12651D01*
Y-12618D01*
X460620D01*
Y-12586D01*
X460653D01*
Y-12554D01*
Y-12521D01*
X460685D01*
Y-12489D01*
X460717D01*
Y-12457D01*
X460750D01*
Y-12425D01*
X460782D01*
Y-12392D01*
X460814D01*
Y-12360D01*
X460846D01*
Y-12328D01*
X460911D01*
Y-12296D01*
X460943D01*
Y-12263D01*
X461008D01*
Y-12231D01*
X461072D01*
Y-12199D01*
X461137D01*
Y-12167D01*
X461234D01*
Y-12134D01*
X461330D01*
Y-12102D01*
X461879D01*
Y-12134D01*
D02*
G37*
G36*
X584252Y-17717D02*
X566535D01*
Y-16929D01*
X565354D01*
Y16142D01*
X584252D01*
Y-17717D01*
D02*
G37*
G36*
X101558Y-22740D02*
X104134D01*
Y-32677D01*
X80587D01*
Y-44488D01*
X70472D01*
Y-34646D01*
X64173D01*
Y-30331D01*
X64189D01*
Y-25197D01*
X71260D01*
Y-18504D01*
X84925D01*
X85469Y-18729D01*
X86185D01*
X86729Y-18504D01*
X88157D01*
Y-18579D01*
X92158D01*
Y-18504D01*
X93258D01*
Y-17541D01*
X101558D01*
Y-22740D01*
D02*
G37*
G36*
X457168Y14449D02*
X457491D01*
Y14417D01*
X457620D01*
Y14385D01*
X457749D01*
Y14353D01*
X457814D01*
Y14320D01*
X457911D01*
Y14288D01*
X457975D01*
Y14256D01*
X458040D01*
Y14224D01*
X458104D01*
Y14191D01*
X458169D01*
Y14159D01*
X458201D01*
Y14127D01*
X458265D01*
Y14095D01*
X458298D01*
Y14062D01*
X458330D01*
Y14030D01*
X458394D01*
Y13998D01*
X458427D01*
Y13965D01*
X458459D01*
Y13933D01*
X458491D01*
Y13901D01*
X458524D01*
Y13869D01*
X458556D01*
Y13836D01*
X458588D01*
Y13804D01*
X458620D01*
Y13772D01*
X458653D01*
Y13740D01*
Y13707D01*
X458685D01*
Y13675D01*
X458717D01*
Y13643D01*
X458749D01*
Y13611D01*
Y13578D01*
X458782D01*
Y13546D01*
X458814D01*
Y13514D01*
Y13482D01*
X458846D01*
Y13449D01*
Y13417D01*
X458878D01*
Y13385D01*
Y13352D01*
X458911D01*
Y13320D01*
Y13288D01*
X458943D01*
Y13256D01*
Y13223D01*
Y13191D01*
X458975D01*
Y13159D01*
Y13127D01*
X459008D01*
Y13094D01*
Y13062D01*
Y13030D01*
Y12998D01*
X459040D01*
Y12965D01*
Y12933D01*
Y12901D01*
Y12869D01*
Y12836D01*
X459072D01*
Y12804D01*
Y12772D01*
Y12740D01*
Y12707D01*
Y12675D01*
Y12643D01*
Y12610D01*
Y12578D01*
Y12546D01*
Y12514D01*
Y12481D01*
Y12449D01*
Y12417D01*
Y12385D01*
Y12352D01*
Y12320D01*
Y12288D01*
Y12256D01*
Y12223D01*
Y12191D01*
Y12159D01*
Y12127D01*
Y12094D01*
Y12062D01*
Y12030D01*
Y11998D01*
Y11965D01*
Y11933D01*
Y11901D01*
Y11868D01*
Y11836D01*
Y11804D01*
Y11772D01*
Y11739D01*
Y11707D01*
Y11675D01*
Y11643D01*
Y11610D01*
Y11578D01*
Y11546D01*
Y11514D01*
Y11481D01*
Y11449D01*
Y11417D01*
Y11384D01*
Y11352D01*
Y11320D01*
Y11288D01*
Y11255D01*
Y11223D01*
Y11191D01*
Y11159D01*
Y11126D01*
Y11094D01*
Y11062D01*
Y11030D01*
Y10997D01*
Y10965D01*
Y10933D01*
Y10901D01*
Y10868D01*
Y10836D01*
Y10804D01*
Y10772D01*
Y10739D01*
Y10707D01*
Y10675D01*
Y10643D01*
Y10610D01*
Y10578D01*
Y10546D01*
Y10514D01*
Y10481D01*
Y10449D01*
Y10417D01*
Y10384D01*
Y10352D01*
Y10320D01*
Y10288D01*
Y10255D01*
Y10223D01*
Y10191D01*
Y10159D01*
Y10126D01*
Y10094D01*
Y10062D01*
Y10029D01*
Y9997D01*
Y9965D01*
Y9933D01*
Y9900D01*
Y9868D01*
Y9836D01*
Y9804D01*
Y9771D01*
Y9739D01*
Y9707D01*
Y9675D01*
Y9642D01*
Y9610D01*
Y9578D01*
Y9546D01*
Y9513D01*
Y9481D01*
Y9449D01*
Y9417D01*
Y9384D01*
Y9352D01*
Y9320D01*
Y9287D01*
Y9255D01*
Y9223D01*
Y9191D01*
Y9159D01*
Y9126D01*
Y9094D01*
Y9062D01*
Y9029D01*
Y8997D01*
Y8965D01*
Y8933D01*
Y8900D01*
Y8868D01*
Y8836D01*
Y8804D01*
Y8771D01*
Y8739D01*
Y8707D01*
Y8675D01*
Y8642D01*
Y8610D01*
Y8578D01*
Y8546D01*
Y8513D01*
Y8481D01*
Y8449D01*
Y8416D01*
Y8384D01*
Y8352D01*
Y8320D01*
Y8287D01*
Y8255D01*
Y8223D01*
Y8191D01*
Y8158D01*
Y8126D01*
Y8094D01*
Y8062D01*
Y8029D01*
Y7997D01*
Y7965D01*
Y7932D01*
Y7900D01*
Y7868D01*
Y7836D01*
Y7803D01*
Y7771D01*
Y7739D01*
Y7707D01*
Y7674D01*
Y7642D01*
Y7610D01*
Y7578D01*
Y7545D01*
Y7513D01*
Y7481D01*
Y7449D01*
Y7416D01*
Y7384D01*
Y7352D01*
Y7320D01*
Y7287D01*
Y7255D01*
Y7223D01*
Y7191D01*
Y7158D01*
Y7126D01*
Y7094D01*
Y7062D01*
Y7029D01*
Y6997D01*
Y6965D01*
Y6932D01*
Y6900D01*
Y6868D01*
Y6836D01*
Y6803D01*
Y6771D01*
Y6739D01*
Y6707D01*
Y6674D01*
Y6642D01*
Y6610D01*
Y6577D01*
Y6545D01*
Y6513D01*
Y6481D01*
Y6448D01*
Y6416D01*
Y6384D01*
Y6352D01*
Y6319D01*
Y6287D01*
Y6255D01*
Y6223D01*
Y6190D01*
Y6158D01*
Y6126D01*
Y6094D01*
Y6061D01*
Y6029D01*
Y5997D01*
Y5965D01*
Y5932D01*
Y5900D01*
Y5868D01*
Y5835D01*
Y5803D01*
Y5771D01*
Y5739D01*
Y5706D01*
Y5674D01*
Y5642D01*
Y5610D01*
Y5577D01*
Y5545D01*
Y5513D01*
Y5481D01*
Y5448D01*
Y5416D01*
Y5384D01*
Y5352D01*
Y5319D01*
Y5287D01*
Y5255D01*
Y5223D01*
Y5190D01*
Y5158D01*
Y5126D01*
Y5094D01*
Y5061D01*
Y5029D01*
Y4997D01*
Y4964D01*
Y4932D01*
Y4900D01*
Y4868D01*
Y4835D01*
Y4803D01*
Y4771D01*
Y4739D01*
Y4706D01*
Y4674D01*
Y4642D01*
Y4610D01*
Y4577D01*
Y4545D01*
Y4513D01*
Y4481D01*
Y4448D01*
Y4416D01*
Y4384D01*
Y4352D01*
Y4319D01*
Y4287D01*
Y4255D01*
Y4222D01*
Y4190D01*
Y4158D01*
Y4126D01*
Y4093D01*
Y4061D01*
Y4029D01*
Y3997D01*
Y3964D01*
Y3932D01*
Y3900D01*
Y3867D01*
Y3835D01*
Y3803D01*
Y3771D01*
Y3739D01*
Y3706D01*
Y3674D01*
Y3642D01*
Y3609D01*
Y3577D01*
Y3545D01*
Y3513D01*
Y3480D01*
Y3448D01*
Y3416D01*
Y3384D01*
Y3351D01*
Y3319D01*
Y3287D01*
Y3255D01*
Y3222D01*
Y3190D01*
Y3158D01*
Y3125D01*
Y3093D01*
Y3061D01*
Y3029D01*
Y2997D01*
Y2964D01*
Y2932D01*
Y2900D01*
Y2867D01*
Y2835D01*
Y2803D01*
Y2771D01*
Y2738D01*
Y2706D01*
Y2674D01*
Y2642D01*
Y2609D01*
Y2577D01*
Y2545D01*
Y2513D01*
Y2480D01*
Y2448D01*
Y2416D01*
Y2383D01*
Y2351D01*
Y2319D01*
Y2287D01*
Y2254D01*
Y2222D01*
Y2190D01*
Y2158D01*
Y2125D01*
Y2093D01*
Y2061D01*
Y2029D01*
Y1996D01*
Y1964D01*
Y1932D01*
Y1900D01*
Y1867D01*
Y1835D01*
Y1803D01*
Y1770D01*
Y1738D01*
Y1706D01*
Y1674D01*
Y1641D01*
Y1609D01*
Y1577D01*
Y1545D01*
Y1512D01*
Y1480D01*
Y1448D01*
Y1416D01*
Y1383D01*
Y1351D01*
Y1319D01*
Y1287D01*
Y1254D01*
Y1222D01*
Y1190D01*
Y1158D01*
Y1125D01*
Y1093D01*
Y1061D01*
Y1029D01*
Y996D01*
Y964D01*
Y932D01*
Y900D01*
Y867D01*
Y835D01*
Y803D01*
Y770D01*
Y738D01*
Y706D01*
Y674D01*
Y641D01*
Y609D01*
Y577D01*
Y545D01*
Y512D01*
Y480D01*
Y448D01*
Y416D01*
Y383D01*
Y351D01*
Y319D01*
Y286D01*
Y254D01*
Y222D01*
Y190D01*
Y157D01*
Y125D01*
Y93D01*
Y61D01*
Y28D01*
Y-4D01*
Y-36D01*
Y-68D01*
Y-101D01*
Y-133D01*
Y-165D01*
Y-197D01*
Y-230D01*
Y-262D01*
Y-294D01*
Y-326D01*
Y-359D01*
Y-391D01*
Y-423D01*
Y-455D01*
Y-488D01*
Y-520D01*
Y-552D01*
Y-585D01*
Y-617D01*
Y-649D01*
Y-681D01*
Y-714D01*
Y-746D01*
Y-778D01*
Y-810D01*
Y-843D01*
Y-875D01*
Y-907D01*
Y-939D01*
Y-972D01*
Y-1004D01*
Y-1036D01*
Y-1068D01*
Y-1101D01*
Y-1133D01*
Y-1165D01*
Y-1198D01*
Y-1230D01*
Y-1262D01*
Y-1294D01*
Y-1327D01*
Y-1359D01*
Y-1391D01*
Y-1423D01*
Y-1456D01*
Y-1488D01*
Y-1520D01*
Y-1552D01*
Y-1585D01*
Y-1617D01*
Y-1649D01*
Y-1681D01*
Y-1714D01*
Y-1746D01*
Y-1778D01*
Y-1811D01*
Y-1843D01*
Y-1875D01*
Y-1907D01*
Y-1940D01*
Y-1972D01*
Y-2004D01*
Y-2036D01*
Y-2069D01*
Y-2101D01*
Y-2133D01*
Y-2165D01*
Y-2198D01*
Y-2230D01*
Y-2262D01*
Y-2294D01*
Y-2327D01*
Y-2359D01*
Y-2391D01*
Y-2424D01*
Y-2456D01*
Y-2488D01*
Y-2520D01*
Y-2553D01*
Y-2585D01*
Y-2617D01*
Y-2649D01*
Y-2682D01*
Y-2714D01*
Y-2746D01*
Y-2778D01*
Y-2811D01*
Y-2843D01*
Y-2875D01*
Y-2907D01*
Y-2940D01*
Y-2972D01*
Y-3004D01*
Y-3036D01*
Y-3069D01*
Y-3101D01*
Y-3133D01*
Y-3165D01*
Y-3198D01*
Y-3230D01*
Y-3262D01*
Y-3295D01*
Y-3327D01*
Y-3359D01*
Y-3391D01*
Y-3424D01*
Y-3456D01*
Y-3488D01*
Y-3520D01*
Y-3553D01*
Y-3585D01*
Y-3617D01*
Y-3650D01*
Y-3682D01*
Y-3714D01*
Y-3746D01*
Y-3779D01*
Y-3811D01*
Y-3843D01*
Y-3875D01*
Y-3907D01*
Y-3940D01*
Y-3972D01*
Y-4004D01*
Y-4037D01*
Y-4069D01*
Y-4101D01*
Y-4133D01*
Y-4166D01*
Y-4198D01*
Y-4230D01*
Y-4262D01*
Y-4295D01*
Y-4327D01*
Y-4359D01*
Y-4391D01*
Y-4424D01*
Y-4456D01*
Y-4488D01*
Y-4521D01*
Y-4553D01*
Y-4585D01*
Y-4617D01*
Y-4650D01*
Y-4682D01*
Y-4714D01*
Y-4746D01*
Y-4779D01*
Y-4811D01*
Y-4843D01*
Y-4875D01*
Y-4908D01*
Y-4940D01*
Y-4972D01*
Y-5004D01*
Y-5037D01*
Y-5069D01*
Y-5101D01*
Y-5133D01*
Y-5166D01*
Y-5198D01*
Y-5230D01*
Y-5263D01*
Y-5295D01*
Y-5327D01*
Y-5359D01*
Y-5392D01*
Y-5424D01*
Y-5456D01*
Y-5488D01*
Y-5521D01*
Y-5553D01*
Y-5585D01*
Y-5617D01*
Y-5650D01*
Y-5682D01*
Y-5714D01*
Y-5746D01*
Y-5779D01*
Y-5811D01*
Y-5843D01*
Y-5875D01*
Y-5908D01*
Y-5940D01*
Y-5972D01*
Y-6005D01*
Y-6037D01*
Y-6069D01*
Y-6101D01*
Y-6134D01*
Y-6166D01*
Y-6198D01*
Y-6230D01*
Y-6263D01*
Y-6295D01*
Y-6327D01*
Y-6359D01*
Y-6392D01*
Y-6424D01*
Y-6456D01*
Y-6488D01*
Y-6521D01*
Y-6553D01*
Y-6585D01*
Y-6617D01*
Y-6650D01*
Y-6682D01*
Y-6714D01*
Y-6747D01*
Y-6779D01*
Y-6811D01*
Y-6843D01*
Y-6876D01*
Y-6908D01*
Y-6940D01*
Y-6972D01*
Y-7005D01*
Y-7037D01*
Y-7069D01*
Y-7102D01*
Y-7134D01*
Y-7166D01*
Y-7198D01*
Y-7231D01*
Y-7263D01*
Y-7295D01*
Y-7327D01*
Y-7360D01*
Y-7392D01*
Y-7424D01*
Y-7456D01*
Y-7489D01*
Y-7521D01*
Y-7553D01*
Y-7585D01*
Y-7618D01*
Y-7650D01*
Y-7682D01*
Y-7714D01*
Y-7747D01*
Y-7779D01*
Y-7811D01*
Y-7843D01*
Y-7876D01*
Y-7908D01*
Y-7940D01*
Y-7972D01*
Y-8005D01*
Y-8037D01*
Y-8069D01*
Y-8102D01*
Y-8134D01*
Y-8166D01*
Y-8198D01*
Y-8231D01*
Y-8263D01*
Y-8295D01*
Y-8327D01*
Y-8360D01*
Y-8392D01*
Y-8424D01*
Y-8456D01*
Y-8489D01*
Y-8521D01*
Y-8553D01*
Y-8585D01*
Y-8618D01*
Y-8650D01*
Y-8682D01*
Y-8715D01*
Y-8747D01*
Y-8779D01*
Y-8811D01*
Y-8844D01*
Y-8876D01*
Y-8908D01*
Y-8940D01*
Y-8973D01*
Y-9005D01*
Y-9037D01*
Y-9069D01*
Y-9102D01*
Y-9134D01*
Y-9166D01*
Y-9199D01*
Y-9231D01*
Y-9263D01*
Y-9295D01*
Y-9328D01*
Y-9360D01*
Y-9392D01*
Y-9424D01*
Y-9457D01*
Y-9489D01*
Y-9521D01*
Y-9553D01*
Y-9586D01*
Y-9618D01*
Y-9650D01*
Y-9682D01*
Y-9715D01*
Y-9747D01*
Y-9779D01*
Y-9811D01*
Y-9844D01*
Y-9876D01*
Y-9908D01*
Y-9940D01*
Y-9973D01*
Y-10005D01*
Y-10037D01*
Y-10069D01*
Y-10102D01*
Y-10134D01*
Y-10166D01*
Y-10199D01*
Y-10231D01*
Y-10263D01*
Y-10295D01*
Y-10328D01*
Y-10360D01*
Y-10392D01*
Y-10424D01*
Y-10457D01*
Y-10489D01*
Y-10521D01*
Y-10554D01*
Y-10586D01*
Y-10618D01*
Y-10650D01*
Y-10683D01*
Y-10715D01*
Y-10747D01*
Y-10779D01*
Y-10812D01*
Y-10844D01*
Y-10876D01*
Y-10908D01*
Y-10941D01*
Y-10973D01*
Y-11005D01*
Y-11037D01*
Y-11070D01*
Y-11102D01*
Y-11134D01*
Y-11167D01*
Y-11199D01*
Y-11231D01*
Y-11263D01*
Y-11295D01*
Y-11328D01*
Y-11360D01*
Y-11392D01*
Y-11425D01*
Y-11457D01*
Y-11489D01*
Y-11521D01*
Y-11554D01*
Y-11586D01*
Y-11618D01*
Y-11650D01*
Y-11683D01*
Y-11715D01*
Y-11747D01*
Y-11779D01*
Y-11812D01*
Y-11844D01*
Y-11876D01*
Y-11908D01*
Y-11941D01*
Y-11973D01*
Y-12005D01*
Y-12037D01*
Y-12070D01*
Y-12102D01*
Y-12134D01*
Y-12167D01*
Y-12199D01*
Y-12231D01*
Y-12263D01*
Y-12296D01*
Y-12328D01*
Y-12360D01*
Y-12392D01*
Y-12425D01*
Y-12457D01*
Y-12489D01*
Y-12521D01*
Y-12554D01*
Y-12586D01*
Y-12618D01*
Y-12651D01*
Y-12683D01*
Y-12715D01*
Y-12747D01*
Y-12780D01*
Y-12812D01*
Y-12844D01*
Y-12876D01*
Y-12909D01*
Y-12941D01*
Y-12973D01*
Y-13005D01*
Y-13038D01*
Y-13070D01*
Y-13102D01*
Y-13134D01*
Y-13167D01*
Y-13199D01*
Y-13231D01*
Y-13263D01*
Y-13296D01*
Y-13328D01*
Y-13360D01*
Y-13393D01*
Y-13425D01*
Y-13457D01*
Y-13489D01*
Y-13522D01*
Y-13554D01*
Y-13586D01*
Y-13618D01*
Y-13651D01*
Y-13683D01*
Y-13715D01*
Y-13747D01*
Y-13780D01*
Y-13812D01*
Y-13844D01*
Y-13876D01*
Y-13909D01*
Y-13941D01*
Y-13973D01*
Y-14006D01*
Y-14038D01*
Y-14070D01*
Y-14102D01*
Y-14134D01*
Y-14167D01*
Y-14199D01*
Y-14231D01*
Y-14264D01*
Y-14296D01*
Y-14328D01*
Y-14360D01*
Y-14393D01*
Y-14425D01*
Y-14457D01*
Y-14489D01*
Y-14522D01*
Y-14554D01*
Y-14586D01*
Y-14618D01*
Y-14651D01*
Y-14683D01*
Y-14715D01*
Y-14748D01*
Y-14780D01*
Y-14812D01*
Y-14844D01*
Y-14877D01*
Y-14909D01*
Y-14941D01*
Y-14973D01*
Y-15006D01*
Y-15038D01*
Y-15070D01*
Y-15102D01*
Y-15135D01*
Y-15167D01*
Y-15199D01*
Y-15231D01*
Y-15264D01*
Y-15296D01*
Y-15328D01*
Y-15360D01*
Y-15393D01*
Y-15425D01*
Y-15457D01*
Y-15489D01*
Y-15522D01*
Y-15554D01*
Y-15586D01*
Y-15619D01*
Y-15651D01*
Y-15683D01*
Y-15715D01*
Y-15748D01*
Y-15780D01*
Y-15812D01*
Y-15844D01*
Y-15877D01*
Y-15909D01*
Y-15941D01*
Y-15973D01*
Y-16006D01*
Y-16038D01*
Y-16070D01*
Y-16103D01*
Y-16135D01*
Y-16167D01*
Y-16199D01*
Y-16232D01*
Y-16264D01*
Y-16296D01*
Y-16328D01*
Y-16361D01*
Y-16393D01*
Y-16425D01*
Y-16457D01*
Y-16490D01*
Y-16522D01*
Y-16554D01*
Y-16586D01*
Y-16619D01*
Y-16651D01*
Y-16683D01*
Y-16715D01*
Y-16748D01*
Y-16780D01*
Y-16812D01*
Y-16845D01*
Y-16877D01*
Y-16909D01*
Y-16941D01*
Y-16974D01*
Y-17006D01*
Y-17038D01*
Y-17070D01*
Y-17103D01*
Y-17135D01*
Y-17167D01*
Y-17199D01*
Y-17232D01*
Y-17264D01*
Y-17296D01*
Y-17328D01*
Y-17361D01*
Y-17393D01*
Y-17425D01*
Y-17458D01*
Y-17490D01*
Y-17522D01*
Y-17554D01*
Y-17586D01*
Y-17619D01*
Y-17651D01*
Y-17683D01*
Y-17716D01*
Y-17748D01*
Y-17780D01*
Y-17812D01*
Y-17845D01*
Y-17877D01*
Y-17909D01*
Y-17941D01*
Y-17974D01*
Y-18006D01*
Y-18038D01*
Y-18070D01*
Y-18103D01*
Y-18135D01*
Y-18167D01*
Y-18200D01*
Y-18232D01*
Y-18264D01*
Y-18296D01*
Y-18329D01*
Y-18361D01*
Y-18393D01*
Y-18425D01*
Y-18458D01*
Y-18490D01*
Y-18522D01*
Y-18554D01*
Y-18587D01*
Y-18619D01*
Y-18651D01*
Y-18683D01*
Y-18716D01*
Y-18748D01*
Y-18780D01*
Y-18812D01*
Y-18845D01*
Y-18877D01*
Y-18909D01*
Y-18941D01*
Y-18974D01*
Y-19006D01*
Y-19038D01*
Y-19071D01*
Y-19103D01*
Y-19135D01*
Y-19167D01*
Y-19200D01*
Y-19232D01*
Y-19264D01*
Y-19296D01*
Y-19329D01*
Y-19361D01*
Y-19393D01*
Y-19425D01*
Y-19458D01*
Y-19490D01*
Y-19522D01*
Y-19555D01*
Y-19587D01*
Y-19619D01*
Y-19651D01*
Y-19684D01*
Y-19716D01*
Y-19748D01*
Y-19780D01*
Y-19813D01*
Y-19845D01*
Y-19877D01*
Y-19909D01*
Y-19942D01*
Y-19974D01*
Y-20006D01*
Y-20039D01*
Y-20071D01*
Y-20103D01*
Y-20135D01*
Y-20167D01*
Y-20200D01*
Y-20232D01*
Y-20264D01*
Y-20297D01*
Y-20329D01*
Y-20361D01*
Y-20393D01*
Y-20426D01*
Y-20458D01*
Y-20490D01*
Y-20522D01*
Y-20555D01*
Y-20587D01*
Y-20619D01*
Y-20651D01*
Y-20684D01*
Y-20716D01*
Y-20748D01*
Y-20780D01*
Y-20813D01*
Y-20845D01*
Y-20877D01*
Y-20910D01*
Y-20942D01*
Y-20974D01*
Y-21006D01*
Y-21039D01*
Y-21071D01*
Y-21103D01*
Y-21135D01*
Y-21168D01*
Y-21200D01*
Y-21232D01*
Y-21264D01*
Y-21297D01*
Y-21329D01*
Y-21361D01*
Y-21393D01*
Y-21426D01*
Y-21458D01*
Y-21490D01*
Y-21522D01*
Y-21555D01*
Y-21587D01*
Y-21619D01*
Y-21652D01*
Y-21684D01*
Y-21716D01*
Y-21748D01*
Y-21781D01*
Y-21813D01*
Y-21845D01*
Y-21877D01*
Y-21910D01*
Y-21942D01*
Y-21974D01*
Y-22006D01*
Y-22039D01*
Y-22071D01*
Y-22103D01*
Y-22136D01*
Y-22168D01*
Y-22200D01*
Y-22232D01*
Y-22264D01*
Y-22297D01*
Y-22329D01*
Y-22361D01*
Y-22394D01*
X457878D01*
Y-22361D01*
Y-22329D01*
Y-22297D01*
Y-22264D01*
Y-22232D01*
Y-22200D01*
Y-22168D01*
Y-22136D01*
Y-22103D01*
Y-22071D01*
Y-22039D01*
Y-22006D01*
Y-21974D01*
Y-21942D01*
Y-21910D01*
Y-21877D01*
Y-21845D01*
Y-21813D01*
Y-21781D01*
Y-21748D01*
Y-21716D01*
Y-21684D01*
Y-21652D01*
Y-21619D01*
Y-21587D01*
Y-21555D01*
Y-21522D01*
Y-21490D01*
Y-21458D01*
Y-21426D01*
Y-21393D01*
Y-21361D01*
Y-21329D01*
Y-21297D01*
Y-21264D01*
Y-21232D01*
Y-21200D01*
Y-21168D01*
Y-21135D01*
Y-21103D01*
Y-21071D01*
Y-21039D01*
Y-21006D01*
Y-20974D01*
Y-20942D01*
Y-20910D01*
Y-20877D01*
Y-20845D01*
Y-20813D01*
Y-20780D01*
Y-20748D01*
Y-20716D01*
Y-20684D01*
Y-20651D01*
Y-20619D01*
Y-20587D01*
Y-20555D01*
Y-20522D01*
Y-20490D01*
Y-20458D01*
Y-20426D01*
Y-20393D01*
Y-20361D01*
Y-20329D01*
Y-20297D01*
Y-20264D01*
Y-20232D01*
Y-20200D01*
Y-20167D01*
Y-20135D01*
Y-20103D01*
Y-20071D01*
Y-20039D01*
Y-20006D01*
Y-19974D01*
Y-19942D01*
Y-19909D01*
Y-19877D01*
Y-19845D01*
Y-19813D01*
Y-19780D01*
Y-19748D01*
Y-19716D01*
Y-19684D01*
Y-19651D01*
Y-19619D01*
Y-19587D01*
Y-19555D01*
Y-19522D01*
Y-19490D01*
Y-19458D01*
Y-19425D01*
Y-19393D01*
Y-19361D01*
Y-19329D01*
Y-19296D01*
Y-19264D01*
Y-19232D01*
Y-19200D01*
Y-19167D01*
Y-19135D01*
Y-19103D01*
Y-19071D01*
Y-19038D01*
Y-19006D01*
Y-18974D01*
Y-18941D01*
Y-18909D01*
Y-18877D01*
Y-18845D01*
Y-18812D01*
Y-18780D01*
Y-18748D01*
Y-18716D01*
Y-18683D01*
Y-18651D01*
Y-18619D01*
Y-18587D01*
Y-18554D01*
Y-18522D01*
Y-18490D01*
Y-18458D01*
Y-18425D01*
Y-18393D01*
Y-18361D01*
Y-18329D01*
Y-18296D01*
Y-18264D01*
Y-18232D01*
Y-18200D01*
Y-18167D01*
Y-18135D01*
Y-18103D01*
Y-18070D01*
Y-18038D01*
Y-18006D01*
Y-17974D01*
Y-17941D01*
Y-17909D01*
Y-17877D01*
Y-17845D01*
Y-17812D01*
Y-17780D01*
Y-17748D01*
Y-17716D01*
Y-17683D01*
Y-17651D01*
Y-17619D01*
Y-17586D01*
Y-17554D01*
Y-17522D01*
Y-17490D01*
Y-17458D01*
Y-17425D01*
Y-17393D01*
Y-17361D01*
Y-17328D01*
Y-17296D01*
Y-17264D01*
Y-17232D01*
Y-17199D01*
Y-17167D01*
Y-17135D01*
Y-17103D01*
Y-17070D01*
Y-17038D01*
Y-17006D01*
Y-16974D01*
Y-16941D01*
Y-16909D01*
Y-16877D01*
Y-16845D01*
Y-16812D01*
Y-16780D01*
Y-16748D01*
Y-16715D01*
Y-16683D01*
Y-16651D01*
Y-16619D01*
Y-16586D01*
Y-16554D01*
Y-16522D01*
Y-16490D01*
Y-16457D01*
Y-16425D01*
Y-16393D01*
Y-16361D01*
Y-16328D01*
Y-16296D01*
Y-16264D01*
Y-16232D01*
Y-16199D01*
Y-16167D01*
Y-16135D01*
Y-16103D01*
Y-16070D01*
Y-16038D01*
Y-16006D01*
Y-15973D01*
Y-15941D01*
Y-15909D01*
Y-15877D01*
Y-15844D01*
Y-15812D01*
Y-15780D01*
Y-15748D01*
Y-15715D01*
Y-15683D01*
Y-15651D01*
Y-15619D01*
Y-15586D01*
Y-15554D01*
Y-15522D01*
Y-15489D01*
Y-15457D01*
Y-15425D01*
Y-15393D01*
Y-15360D01*
Y-15328D01*
Y-15296D01*
Y-15264D01*
Y-15231D01*
Y-15199D01*
Y-15167D01*
Y-15135D01*
Y-15102D01*
Y-15070D01*
Y-15038D01*
Y-15006D01*
Y-14973D01*
Y-14941D01*
Y-14909D01*
Y-14877D01*
Y-14844D01*
Y-14812D01*
Y-14780D01*
Y-14748D01*
Y-14715D01*
Y-14683D01*
Y-14651D01*
Y-14618D01*
Y-14586D01*
Y-14554D01*
Y-14522D01*
Y-14489D01*
Y-14457D01*
Y-14425D01*
Y-14393D01*
Y-14360D01*
Y-14328D01*
Y-14296D01*
Y-14264D01*
Y-14231D01*
Y-14199D01*
Y-14167D01*
Y-14134D01*
Y-14102D01*
Y-14070D01*
Y-14038D01*
Y-14006D01*
Y-13973D01*
Y-13941D01*
Y-13909D01*
Y-13876D01*
Y-13844D01*
Y-13812D01*
Y-13780D01*
Y-13747D01*
Y-13715D01*
Y-13683D01*
Y-13651D01*
Y-13618D01*
Y-13586D01*
Y-13554D01*
Y-13522D01*
Y-13489D01*
Y-13457D01*
Y-13425D01*
Y-13393D01*
Y-13360D01*
Y-13328D01*
Y-13296D01*
Y-13263D01*
Y-13231D01*
Y-13199D01*
Y-13167D01*
Y-13134D01*
Y-13102D01*
Y-13070D01*
Y-13038D01*
Y-13005D01*
Y-12973D01*
Y-12941D01*
Y-12909D01*
Y-12876D01*
Y-12844D01*
Y-12812D01*
Y-12780D01*
Y-12747D01*
Y-12715D01*
Y-12683D01*
Y-12651D01*
Y-12618D01*
Y-12586D01*
Y-12554D01*
Y-12521D01*
Y-12489D01*
Y-12457D01*
Y-12425D01*
Y-12392D01*
Y-12360D01*
Y-12328D01*
Y-12296D01*
Y-12263D01*
Y-12231D01*
Y-12199D01*
Y-12167D01*
Y-12134D01*
Y-12102D01*
Y-12070D01*
Y-12037D01*
Y-12005D01*
Y-11973D01*
Y-11941D01*
Y-11908D01*
Y-11876D01*
Y-11844D01*
Y-11812D01*
Y-11779D01*
Y-11747D01*
Y-11715D01*
Y-11683D01*
Y-11650D01*
Y-11618D01*
Y-11586D01*
Y-11554D01*
Y-11521D01*
Y-11489D01*
Y-11457D01*
Y-11425D01*
Y-11392D01*
Y-11360D01*
Y-11328D01*
Y-11295D01*
Y-11263D01*
Y-11231D01*
Y-11199D01*
Y-11167D01*
Y-11134D01*
Y-11102D01*
Y-11070D01*
Y-11037D01*
Y-11005D01*
Y-10973D01*
Y-10941D01*
Y-10908D01*
Y-10876D01*
Y-10844D01*
Y-10812D01*
Y-10779D01*
Y-10747D01*
Y-10715D01*
Y-10683D01*
Y-10650D01*
Y-10618D01*
Y-10586D01*
Y-10554D01*
Y-10521D01*
Y-10489D01*
Y-10457D01*
Y-10424D01*
Y-10392D01*
Y-10360D01*
Y-10328D01*
Y-10295D01*
Y-10263D01*
Y-10231D01*
Y-10199D01*
Y-10166D01*
Y-10134D01*
Y-10102D01*
Y-10069D01*
Y-10037D01*
Y-10005D01*
Y-9973D01*
Y-9940D01*
Y-9908D01*
Y-9876D01*
Y-9844D01*
Y-9811D01*
Y-9779D01*
Y-9747D01*
Y-9715D01*
Y-9682D01*
Y-9650D01*
Y-9618D01*
Y-9586D01*
Y-9553D01*
Y-9521D01*
Y-9489D01*
Y-9457D01*
Y-9424D01*
Y-9392D01*
Y-9360D01*
Y-9328D01*
Y-9295D01*
Y-9263D01*
Y-9231D01*
Y-9199D01*
Y-9166D01*
Y-9134D01*
Y-9102D01*
Y-9069D01*
Y-9037D01*
Y-9005D01*
Y-8973D01*
Y-8940D01*
Y-8908D01*
Y-8876D01*
Y-8844D01*
Y-8811D01*
Y-8779D01*
Y-8747D01*
Y-8715D01*
Y-8682D01*
Y-8650D01*
Y-8618D01*
Y-8585D01*
Y-8553D01*
Y-8521D01*
Y-8489D01*
Y-8456D01*
Y-8424D01*
Y-8392D01*
Y-8360D01*
Y-8327D01*
Y-8295D01*
Y-8263D01*
Y-8231D01*
Y-8198D01*
Y-8166D01*
Y-8134D01*
Y-8102D01*
Y-8069D01*
Y-8037D01*
Y-8005D01*
Y-7972D01*
Y-7940D01*
Y-7908D01*
Y-7876D01*
Y-7843D01*
Y-7811D01*
Y-7779D01*
Y-7747D01*
Y-7714D01*
Y-7682D01*
Y-7650D01*
Y-7618D01*
Y-7585D01*
Y-7553D01*
Y-7521D01*
Y-7489D01*
Y-7456D01*
Y-7424D01*
Y-7392D01*
Y-7360D01*
Y-7327D01*
Y-7295D01*
Y-7263D01*
Y-7231D01*
Y-7198D01*
Y-7166D01*
Y-7134D01*
Y-7102D01*
Y-7069D01*
Y-7037D01*
Y-7005D01*
Y-6972D01*
Y-6940D01*
Y-6908D01*
Y-6876D01*
Y-6843D01*
Y-6811D01*
Y-6779D01*
Y-6747D01*
Y-6714D01*
Y-6682D01*
Y-6650D01*
Y-6617D01*
Y-6585D01*
Y-6553D01*
Y-6521D01*
Y-6488D01*
Y-6456D01*
Y-6424D01*
Y-6392D01*
Y-6359D01*
Y-6327D01*
Y-6295D01*
Y-6263D01*
Y-6230D01*
Y-6198D01*
Y-6166D01*
Y-6134D01*
Y-6101D01*
Y-6069D01*
Y-6037D01*
Y-6005D01*
Y-5972D01*
Y-5940D01*
Y-5908D01*
Y-5875D01*
Y-5843D01*
Y-5811D01*
Y-5779D01*
Y-5746D01*
Y-5714D01*
Y-5682D01*
Y-5650D01*
Y-5617D01*
Y-5585D01*
Y-5553D01*
Y-5521D01*
Y-5488D01*
Y-5456D01*
Y-5424D01*
Y-5392D01*
Y-5359D01*
Y-5327D01*
Y-5295D01*
Y-5263D01*
Y-5230D01*
Y-5198D01*
Y-5166D01*
Y-5133D01*
Y-5101D01*
Y-5069D01*
Y-5037D01*
Y-5004D01*
Y-4972D01*
Y-4940D01*
Y-4908D01*
Y-4875D01*
Y-4843D01*
Y-4811D01*
Y-4779D01*
Y-4746D01*
Y-4714D01*
Y-4682D01*
Y-4650D01*
Y-4617D01*
Y-4585D01*
Y-4553D01*
Y-4521D01*
Y-4488D01*
Y-4456D01*
Y-4424D01*
Y-4391D01*
Y-4359D01*
Y-4327D01*
Y-4295D01*
Y-4262D01*
Y-4230D01*
Y-4198D01*
Y-4166D01*
Y-4133D01*
Y-4101D01*
Y-4069D01*
Y-4037D01*
Y-4004D01*
Y-3972D01*
Y-3940D01*
Y-3907D01*
Y-3875D01*
Y-3843D01*
Y-3811D01*
Y-3779D01*
Y-3746D01*
Y-3714D01*
Y-3682D01*
Y-3650D01*
Y-3617D01*
Y-3585D01*
Y-3553D01*
Y-3520D01*
Y-3488D01*
Y-3456D01*
Y-3424D01*
Y-3391D01*
Y-3359D01*
Y-3327D01*
Y-3295D01*
Y-3262D01*
Y-3230D01*
Y-3198D01*
Y-3165D01*
Y-3133D01*
Y-3101D01*
Y-3069D01*
Y-3036D01*
Y-3004D01*
Y-2972D01*
Y-2940D01*
Y-2907D01*
Y-2875D01*
Y-2843D01*
Y-2811D01*
Y-2778D01*
Y-2746D01*
Y-2714D01*
Y-2682D01*
Y-2649D01*
Y-2617D01*
Y-2585D01*
Y-2553D01*
Y-2520D01*
Y-2488D01*
Y-2456D01*
Y-2424D01*
Y-2391D01*
Y-2359D01*
Y-2327D01*
Y-2294D01*
Y-2262D01*
Y-2230D01*
Y-2198D01*
Y-2165D01*
Y-2133D01*
Y-2101D01*
Y-2069D01*
Y-2036D01*
Y-2004D01*
Y-1972D01*
Y-1940D01*
Y-1907D01*
Y-1875D01*
Y-1843D01*
Y-1811D01*
Y-1778D01*
Y-1746D01*
Y-1714D01*
Y-1681D01*
Y-1649D01*
Y-1617D01*
Y-1585D01*
Y-1552D01*
Y-1520D01*
Y-1488D01*
Y-1456D01*
Y-1423D01*
Y-1391D01*
Y-1359D01*
Y-1327D01*
Y-1294D01*
Y-1262D01*
Y-1230D01*
Y-1198D01*
Y-1165D01*
Y-1133D01*
Y-1101D01*
Y-1068D01*
Y-1036D01*
Y-1004D01*
Y-972D01*
Y-939D01*
Y-907D01*
Y-875D01*
Y-843D01*
Y-810D01*
Y-778D01*
Y-746D01*
Y-714D01*
Y-681D01*
Y-649D01*
Y-617D01*
Y-585D01*
Y-552D01*
Y-520D01*
Y-488D01*
Y-455D01*
Y-423D01*
Y-391D01*
Y-359D01*
Y-326D01*
Y-294D01*
Y-262D01*
Y-230D01*
Y-197D01*
Y-165D01*
Y-133D01*
Y-101D01*
Y-68D01*
Y-36D01*
Y-4D01*
Y28D01*
Y61D01*
Y93D01*
Y125D01*
Y157D01*
Y190D01*
Y222D01*
Y254D01*
Y286D01*
Y319D01*
Y351D01*
Y383D01*
Y416D01*
Y448D01*
Y480D01*
Y512D01*
Y545D01*
Y577D01*
Y609D01*
Y641D01*
Y674D01*
Y706D01*
Y738D01*
Y770D01*
Y803D01*
Y835D01*
Y867D01*
Y900D01*
Y932D01*
Y964D01*
Y996D01*
Y1029D01*
Y1061D01*
Y1093D01*
Y1125D01*
Y1158D01*
Y1190D01*
Y1222D01*
Y1254D01*
Y1287D01*
Y1319D01*
Y1351D01*
Y1383D01*
Y1416D01*
Y1448D01*
Y1480D01*
Y1512D01*
Y1545D01*
Y1577D01*
Y1609D01*
Y1641D01*
Y1674D01*
Y1706D01*
Y1738D01*
Y1770D01*
Y1803D01*
Y1835D01*
Y1867D01*
Y1900D01*
Y1932D01*
Y1964D01*
Y1996D01*
Y2029D01*
Y2061D01*
Y2093D01*
Y2125D01*
Y2158D01*
Y2190D01*
Y2222D01*
Y2254D01*
Y2287D01*
Y2319D01*
Y2351D01*
Y2383D01*
Y2416D01*
Y2448D01*
Y2480D01*
Y2513D01*
Y2545D01*
Y2577D01*
Y2609D01*
Y2642D01*
Y2674D01*
Y2706D01*
Y2738D01*
Y2771D01*
Y2803D01*
Y2835D01*
Y2867D01*
Y2900D01*
Y2932D01*
Y2964D01*
Y2997D01*
Y3029D01*
Y3061D01*
Y3093D01*
Y3125D01*
Y3158D01*
Y3190D01*
Y3222D01*
Y3255D01*
Y3287D01*
Y3319D01*
Y3351D01*
Y3384D01*
Y3416D01*
Y3448D01*
Y3480D01*
Y3513D01*
Y3545D01*
Y3577D01*
Y3609D01*
Y3642D01*
Y3674D01*
Y3706D01*
Y3739D01*
Y3771D01*
Y3803D01*
Y3835D01*
Y3867D01*
Y3900D01*
Y3932D01*
Y3964D01*
Y3997D01*
Y4029D01*
Y4061D01*
Y4093D01*
Y4126D01*
Y4158D01*
Y4190D01*
Y4222D01*
Y4255D01*
Y4287D01*
Y4319D01*
Y4352D01*
Y4384D01*
Y4416D01*
Y4448D01*
Y4481D01*
Y4513D01*
Y4545D01*
Y4577D01*
Y4610D01*
Y4642D01*
Y4674D01*
Y4706D01*
Y4739D01*
Y4771D01*
Y4803D01*
Y4835D01*
Y4868D01*
Y4900D01*
Y4932D01*
Y4964D01*
Y4997D01*
Y5029D01*
Y5061D01*
Y5094D01*
Y5126D01*
Y5158D01*
Y5190D01*
Y5223D01*
Y5255D01*
Y5287D01*
Y5319D01*
Y5352D01*
Y5384D01*
Y5416D01*
Y5448D01*
Y5481D01*
Y5513D01*
Y5545D01*
Y5577D01*
Y5610D01*
Y5642D01*
Y5674D01*
Y5706D01*
Y5739D01*
Y5771D01*
Y5803D01*
Y5835D01*
Y5868D01*
Y5900D01*
Y5932D01*
Y5965D01*
Y5997D01*
Y6029D01*
Y6061D01*
Y6094D01*
Y6126D01*
Y6158D01*
Y6190D01*
Y6223D01*
Y6255D01*
Y6287D01*
Y6319D01*
Y6352D01*
Y6384D01*
Y6416D01*
Y6448D01*
Y6481D01*
Y6513D01*
Y6545D01*
Y6577D01*
Y6610D01*
Y6642D01*
Y6674D01*
Y6707D01*
Y6739D01*
Y6771D01*
Y6803D01*
Y6836D01*
Y6868D01*
Y6900D01*
Y6932D01*
Y6965D01*
Y6997D01*
Y7029D01*
Y7062D01*
Y7094D01*
Y7126D01*
Y7158D01*
Y7191D01*
Y7223D01*
Y7255D01*
Y7287D01*
Y7320D01*
Y7352D01*
Y7384D01*
Y7416D01*
Y7449D01*
Y7481D01*
Y7513D01*
Y7545D01*
Y7578D01*
Y7610D01*
Y7642D01*
Y7674D01*
Y7707D01*
Y7739D01*
Y7771D01*
Y7803D01*
Y7836D01*
Y7868D01*
Y7900D01*
Y7932D01*
Y7965D01*
Y7997D01*
Y8029D01*
Y8062D01*
Y8094D01*
Y8126D01*
Y8158D01*
Y8191D01*
Y8223D01*
Y8255D01*
Y8287D01*
Y8320D01*
Y8352D01*
Y8384D01*
Y8416D01*
Y8449D01*
Y8481D01*
Y8513D01*
Y8546D01*
Y8578D01*
Y8610D01*
Y8642D01*
Y8675D01*
Y8707D01*
Y8739D01*
Y8771D01*
Y8804D01*
Y8836D01*
Y8868D01*
Y8900D01*
Y8933D01*
Y8965D01*
Y8997D01*
Y9029D01*
Y9062D01*
Y9094D01*
Y9126D01*
Y9159D01*
Y9191D01*
Y9223D01*
Y9255D01*
Y9287D01*
Y9320D01*
Y9352D01*
Y9384D01*
Y9417D01*
Y9449D01*
Y9481D01*
Y9513D01*
Y9546D01*
Y9578D01*
Y9610D01*
Y9642D01*
Y9675D01*
Y9707D01*
Y9739D01*
Y9771D01*
Y9804D01*
Y9836D01*
Y9868D01*
Y9900D01*
Y9933D01*
Y9965D01*
Y9997D01*
Y10029D01*
Y10062D01*
Y10094D01*
Y10126D01*
Y10159D01*
Y10191D01*
Y10223D01*
Y10255D01*
Y10288D01*
Y10320D01*
Y10352D01*
Y10384D01*
Y10417D01*
Y10449D01*
Y10481D01*
Y10514D01*
Y10546D01*
Y10578D01*
Y10610D01*
Y10643D01*
Y10675D01*
Y10707D01*
Y10739D01*
Y10772D01*
Y10804D01*
Y10836D01*
Y10868D01*
Y10901D01*
Y10933D01*
Y10965D01*
Y10997D01*
Y11030D01*
Y11062D01*
Y11094D01*
Y11126D01*
Y11159D01*
Y11191D01*
Y11223D01*
Y11255D01*
Y11288D01*
Y11320D01*
Y11352D01*
Y11384D01*
Y11417D01*
Y11449D01*
Y11481D01*
Y11514D01*
Y11546D01*
Y11578D01*
Y11610D01*
Y11643D01*
Y11675D01*
Y11707D01*
Y11739D01*
Y11772D01*
Y11804D01*
Y11836D01*
Y11868D01*
Y11901D01*
Y11933D01*
Y11965D01*
Y11998D01*
Y12030D01*
Y12062D01*
Y12094D01*
Y12127D01*
Y12159D01*
Y12191D01*
Y12223D01*
Y12256D01*
Y12288D01*
Y12320D01*
Y12352D01*
Y12385D01*
Y12417D01*
Y12449D01*
Y12481D01*
Y12514D01*
X457846D01*
Y12546D01*
Y12578D01*
Y12610D01*
Y12643D01*
Y12675D01*
X457814D01*
Y12707D01*
Y12740D01*
X457782D01*
Y12772D01*
Y12804D01*
X457749D01*
Y12836D01*
Y12869D01*
X457717D01*
Y12901D01*
X457685D01*
Y12933D01*
Y12965D01*
X457653D01*
Y12998D01*
X457620D01*
Y13030D01*
X457588D01*
Y13062D01*
X457523D01*
Y13094D01*
X457491D01*
Y13127D01*
X457427D01*
Y13159D01*
X457362D01*
Y13191D01*
X457298D01*
Y13223D01*
X457168D01*
Y13256D01*
X453071D01*
Y13288D01*
Y13320D01*
Y13352D01*
Y13385D01*
Y13417D01*
Y13449D01*
Y13482D01*
Y13514D01*
Y13546D01*
Y13578D01*
Y13611D01*
Y13643D01*
Y13675D01*
Y13707D01*
Y13740D01*
Y13772D01*
Y13804D01*
Y13836D01*
Y13869D01*
Y13901D01*
Y13933D01*
Y13965D01*
Y13998D01*
Y14030D01*
Y14062D01*
Y14095D01*
Y14127D01*
Y14159D01*
Y14191D01*
Y14224D01*
Y14256D01*
Y14288D01*
Y14320D01*
Y14353D01*
Y14385D01*
Y14417D01*
Y14449D01*
Y14482D01*
X457168D01*
Y14449D01*
D02*
G37*
G36*
X94882Y-6497D02*
X101558D01*
Y-10197D01*
Y-14790D01*
X101643D01*
Y-14897D01*
X102545D01*
X102643Y-14916D01*
X105243D01*
X105342Y-14897D01*
X106334D01*
X106432Y-14916D01*
X108913D01*
Y-29528D01*
X105512D01*
Y-21041D01*
X102732D01*
Y-16142D01*
X93258D01*
Y-11274D01*
X82677D01*
Y-394D01*
X94882D01*
Y-6497D01*
D02*
G37*
G36*
X602953Y-31299D02*
X595472D01*
Y-21654D01*
X602953D01*
Y-31299D01*
D02*
G37*
G36*
X41437Y-16535D02*
X51968D01*
Y-31594D01*
X38189D01*
Y-24016D01*
X33459D01*
Y-6484D01*
X41437D01*
Y-16535D01*
D02*
G37*
G36*
X561417Y-22047D02*
X551181D01*
Y-24478D01*
X551148Y-24964D01*
X550681Y-24964D01*
X546948D01*
Y-27614D01*
Y-30264D01*
X550681D01*
X551148Y-30264D01*
X551181Y-30751D01*
Y-33858D01*
X522047D01*
Y-10236D01*
X529134D01*
Y0D01*
X544488D01*
Y16535D01*
X561417D01*
Y-22047D01*
D02*
G37*
G36*
X52534Y-9843D02*
X64370D01*
Y-1476D01*
X77953D01*
Y-15748D01*
X68898D01*
Y-23228D01*
X58465D01*
Y-25732D01*
X58380Y-25732D01*
X58380Y-25733D01*
Y-37402D01*
X53150D01*
Y-13780D01*
X44685D01*
Y-1969D01*
X40157D01*
Y21654D01*
X52534D01*
Y-9843D01*
D02*
G37*
G36*
X607087Y-45669D02*
X592913D01*
Y-57087D01*
Y-75197D01*
X572196D01*
Y-52323D01*
X580315D01*
Y-49606D01*
X583071D01*
Y-48720D01*
X586811D01*
Y-39370D01*
X592520D01*
Y-39488D01*
X595472D01*
Y-37205D01*
X607087D01*
Y-45669D01*
D02*
G37*
G36*
X626772Y-37402D02*
X615748D01*
Y-40256D01*
X608661D01*
Y-25591D01*
X626772D01*
Y-37402D01*
D02*
G37*
G36*
X593701Y-36614D02*
X584348D01*
Y-47464D01*
X561048D01*
Y-25764D01*
X593701D01*
Y-36614D01*
D02*
G37*
G36*
X626378Y-56004D02*
X597600D01*
X597250Y-55648D01*
X597378Y-47244D01*
X609646D01*
Y-41634D01*
X626378D01*
Y-56004D01*
D02*
G37*
G36*
X551181Y-50787D02*
X537795D01*
Y-58661D01*
X527953D01*
Y-40551D01*
X551181D01*
Y-50787D01*
D02*
G37*
G36*
X555118Y-75197D02*
X539370D01*
Y-55905D01*
X555118D01*
Y-75197D01*
D02*
G37*
G36*
X121653Y-42172D02*
X94685D01*
Y-67716D01*
X88189D01*
Y-89764D01*
X66929D01*
Y-66535D01*
X82677D01*
Y-33858D01*
X121653D01*
X121653Y-42172D01*
D02*
G37*
G36*
X260630Y-66142D02*
X331351D01*
Y-94095D01*
X237348D01*
Y-9055D01*
X207890D01*
Y-7858D01*
X203839D01*
Y169D01*
X204295D01*
X204957Y442D01*
X205463Y949D01*
X205737Y1610D01*
Y2327D01*
X205463Y2988D01*
X204957Y3494D01*
X204295Y3768D01*
X203839D01*
Y13780D01*
X260630D01*
Y-66142D01*
D02*
G37*
G36*
X187008Y-98228D02*
X186221D01*
Y-96457D01*
X185433D01*
Y-95866D01*
X187008D01*
Y-98228D01*
D02*
G37*
G36*
X446850Y-110443D02*
X438021D01*
X437795Y-110398D01*
X431496D01*
X431271Y-110443D01*
X429330D01*
Y-117044D01*
X421930D01*
Y-108744D01*
X423622D01*
Y-107643D01*
X423697D01*
Y-103643D01*
X423622D01*
Y-102870D01*
X423847Y-102327D01*
Y-101611D01*
X423622Y-101067D01*
Y-96457D01*
X446850D01*
Y-110443D01*
D02*
G37*
G36*
X380020Y-113323D02*
X386676D01*
Y-112730D01*
X391839D01*
X393410Y-112959D01*
Y-125738D01*
X393307D01*
X392761Y-125847D01*
X392555Y-125984D01*
X369133D01*
Y-162992D01*
X355416D01*
Y-120464D01*
X355531Y-119882D01*
X355416Y-119300D01*
Y-115513D01*
X355485D01*
Y-113660D01*
X355578Y-113189D01*
X355485Y-112718D01*
Y-110865D01*
X355416D01*
Y-110290D01*
X359055D01*
Y-116142D01*
X373162D01*
Y-107874D01*
X380020D01*
Y-113323D01*
D02*
G37*
G36*
X437795Y-120240D02*
X437405Y-120318D01*
X437074Y-120539D01*
X437011Y-120634D01*
X430330D01*
X429950Y-120710D01*
X421930D01*
Y-118617D01*
X422359Y-118361D01*
X422656Y-118522D01*
X431496D01*
Y-111417D01*
X437795D01*
Y-120240D01*
D02*
G37*
G36*
X418285Y-124443D02*
X414098D01*
Y-126772D01*
X405905D01*
Y-120894D01*
X413594D01*
Y-120843D01*
X413647D01*
Y-118218D01*
X418285D01*
Y-124443D01*
D02*
G37*
G36*
X-4331Y-38189D02*
X33465D01*
Y-69443D01*
X59449D01*
Y-102201D01*
X50926D01*
X50341Y-102317D01*
X49845Y-102649D01*
X49513Y-103145D01*
X49397Y-103730D01*
Y-106175D01*
X49040D01*
Y-109947D01*
Y-113490D01*
X48609Y-113655D01*
X45891D01*
Y-113655D01*
X45391Y-113792D01*
X45153Y-113554D01*
X44492Y-113280D01*
X43776D01*
X43114Y-113554D01*
X42608Y-114060D01*
X42334Y-114722D01*
Y-115438D01*
X42608Y-116100D01*
X43114Y-116606D01*
X43776Y-116880D01*
X44061D01*
X44172Y-116954D01*
X44757Y-117071D01*
X45891D01*
Y-117427D01*
X52812D01*
Y-113656D01*
X52812D01*
X52812Y-113490D01*
X52913Y-113032D01*
X59449D01*
Y-123104D01*
X54651D01*
Y-128057D01*
X55384D01*
X55662Y-128473D01*
X55622Y-128569D01*
Y-129285D01*
X55896Y-129947D01*
X56231Y-130281D01*
X56024Y-130781D01*
X55537D01*
Y-131890D01*
X-13780D01*
Y-21654D01*
X-4331D01*
Y-38189D01*
D02*
G37*
G36*
X290409Y-132677D02*
X273640D01*
X273290Y-132320D01*
X273480Y-123425D01*
Y-119882D01*
X290409D01*
Y-132677D01*
D02*
G37*
G36*
X417248Y-103643D02*
Y-107643D01*
X418285D01*
Y-117044D01*
X412647D01*
Y-118119D01*
X412628Y-118218D01*
Y-119843D01*
X404724D01*
Y-135039D01*
X419882D01*
Y-139961D01*
X411614D01*
Y-146063D01*
X394488D01*
Y-103543D01*
X416789D01*
X417248Y-103643D01*
D02*
G37*
G36*
X288440Y-146260D02*
X273480D01*
Y-134843D01*
X288440D01*
Y-146260D01*
D02*
G37*
G36*
X462067Y-117736D02*
X456299D01*
Y-131772D01*
X464961D01*
Y-138976D01*
X444410D01*
Y-146850D01*
X434252D01*
Y-127443D01*
X423697D01*
Y-124443D01*
X421930D01*
Y-121729D01*
X430330D01*
Y-121653D01*
X437795D01*
Y-121260D01*
X448425D01*
Y-109902D01*
X462067D01*
Y-117736D01*
D02*
G37*
G36*
X266787Y-156102D02*
X253790D01*
X251039Y-153351D01*
Y-119882D01*
X266787D01*
Y-156102D01*
D02*
G37*
G36*
X288047Y-161221D02*
X274267D01*
Y-149016D01*
X288047D01*
Y-161221D01*
D02*
G37*
G36*
X338189Y-166142D02*
X328346D01*
Y-117717D01*
X338189D01*
Y-166142D01*
D02*
G37*
G36*
X430903Y-151575D02*
X439567D01*
Y-155965D01*
X459883D01*
Y-169291D01*
X432677D01*
Y-155512D01*
X419882D01*
Y-164961D01*
X402854D01*
Y-151575D01*
X416339D01*
Y-142126D01*
X425787D01*
Y-135576D01*
X430903D01*
Y-151575D01*
D02*
G37*
G36*
X35827Y-181840D02*
X29740D01*
Y-181677D01*
X27067D01*
X24394D01*
Y-182890D01*
Y-184858D01*
Y-188795D01*
X29276D01*
X29279Y-189295D01*
X29183Y-189392D01*
X28962Y-189924D01*
X28946Y-189956D01*
X28686Y-190339D01*
Y-190339D01*
X20850D01*
Y-190514D01*
X20350Y-190848D01*
X20040Y-190720D01*
X19324D01*
X18662Y-190994D01*
X18156Y-191500D01*
X17882Y-192162D01*
Y-192878D01*
X18156Y-193539D01*
X18662Y-194046D01*
X19324Y-194320D01*
X20040D01*
X20350Y-194191D01*
X20850Y-194525D01*
Y-194701D01*
X28756D01*
Y-193947D01*
X30709D01*
X31255Y-193839D01*
X31718Y-193529D01*
X32027Y-193066D01*
X32136Y-192520D01*
Y-191529D01*
X32235Y-191431D01*
X32509Y-190769D01*
Y-190053D01*
X32235Y-189392D01*
X32136Y-189293D01*
Y-187766D01*
X32552Y-187488D01*
X32713Y-187555D01*
X33429D01*
X34091Y-187281D01*
X34449Y-186923D01*
X34807Y-187281D01*
X35469Y-187555D01*
X35827D01*
Y-226904D01*
X35620Y-227042D01*
Y-228937D01*
X35120D01*
Y-229437D01*
X33226D01*
X33198Y-229478D01*
X29740D01*
Y-229315D01*
X27067D01*
X24394D01*
Y-230528D01*
Y-232496D01*
Y-236433D01*
X29740D01*
Y-236270D01*
X31889D01*
X33062Y-237443D01*
X32855Y-237943D01*
X29150D01*
Y-237189D01*
X21244D01*
Y-237800D01*
X20744Y-237884D01*
X20705Y-237844D01*
X20043Y-237570D01*
X19327D01*
X18665Y-237844D01*
X18159Y-238351D01*
X17885Y-239012D01*
Y-239728D01*
X18159Y-240390D01*
X18665Y-240896D01*
X19327Y-241170D01*
X20043D01*
X20705Y-240896D01*
X20744Y-240857D01*
X21244Y-240940D01*
Y-241551D01*
X29150D01*
Y-240797D01*
X35039D01*
X35327Y-240740D01*
X35827Y-241083D01*
Y-283755D01*
X35411Y-284032D01*
X35397Y-284027D01*
X34681D01*
X34020Y-284301D01*
X33513Y-284807D01*
X33239Y-285469D01*
Y-285608D01*
X32283Y-286565D01*
X29740D01*
Y-286401D01*
X27067D01*
X24394D01*
Y-287614D01*
Y-289583D01*
Y-293520D01*
X25640D01*
Y-297608D01*
X25541Y-297707D01*
X25267Y-298369D01*
Y-299085D01*
X25541Y-299746D01*
X26047Y-300253D01*
X26709Y-300527D01*
X27425D01*
X28087Y-300253D01*
X28593Y-299746D01*
X28867Y-299085D01*
Y-298369D01*
X28593Y-297707D01*
X28494Y-297608D01*
Y-293520D01*
X29740D01*
Y-291388D01*
X33921D01*
X34020Y-291487D01*
X34681Y-291761D01*
X35397D01*
X35411Y-291755D01*
X35827Y-292033D01*
Y-357087D01*
X-28321D01*
Y-135878D01*
X35827D01*
Y-181840D01*
D02*
G37*
G36*
X309842Y-53937D02*
X516929D01*
Y-140157D01*
X504331D01*
Y-194488D01*
X483465D01*
Y-196014D01*
X483235Y-196123D01*
X482965Y-196167D01*
X482516Y-195718D01*
X481854Y-195444D01*
X481138D01*
X480476Y-195718D01*
X479970Y-196224D01*
X479696Y-196886D01*
Y-197602D01*
X479970Y-198264D01*
X480069Y-198362D01*
Y-219023D01*
X474288Y-224803D01*
X460596D01*
Y-224016D01*
Y-223338D01*
X454694D01*
Y-215354D01*
Y-210928D01*
X452875D01*
Y-207684D01*
X444182D01*
Y-210928D01*
X442316D01*
Y-214961D01*
Y-223338D01*
X436550D01*
Y-224410D01*
Y-224803D01*
X428346D01*
Y-224410D01*
Y-214961D01*
Y-211417D01*
X436601D01*
Y-202741D01*
X436752Y-202515D01*
X436861Y-201969D01*
X436861Y-201969D01*
Y-199334D01*
X436861Y-199334D01*
X436752Y-198788D01*
X436601Y-198562D01*
Y-186261D01*
X473676D01*
Y-118682D01*
X491339D01*
Y-74016D01*
X460055D01*
Y-73803D01*
X454906D01*
Y-74016D01*
X454150D01*
Y-73803D01*
X449000D01*
Y-74016D01*
X332371D01*
Y-66142D01*
X332293Y-65751D01*
X332072Y-65421D01*
X331741Y-65200D01*
X331351Y-65122D01*
X283465D01*
Y-31890D01*
X309842D01*
Y-53937D01*
D02*
G37*
G36*
X279134Y-199016D02*
X278346D01*
Y-197244D01*
X277559D01*
Y-196653D01*
X279134D01*
Y-199016D01*
D02*
G37*
G36*
X324213Y-237008D02*
X321850D01*
Y-236221D01*
X323622D01*
Y-235433D01*
X324213D01*
Y-237008D01*
D02*
G37*
G36*
X574803Y-181203D02*
X582283Y-188683D01*
Y-216929D01*
X578346D01*
Y-237402D01*
X580821D01*
X580870Y-237451D01*
X581532Y-237725D01*
X582248D01*
X582909Y-237451D01*
X582959Y-237402D01*
X585433D01*
Y-258078D01*
X573167D01*
X572882Y-257578D01*
X573060Y-257149D01*
Y-256433D01*
X572786Y-255772D01*
X572280Y-255265D01*
X571618Y-254991D01*
X570902D01*
X570240Y-255265D01*
X570079Y-255427D01*
X569917Y-255265D01*
X569256Y-254991D01*
X568540D01*
X567878Y-255265D01*
X567372Y-255772D01*
X567098Y-256433D01*
Y-257149D01*
X567275Y-257578D01*
X566985Y-258078D01*
X566142D01*
Y-239370D01*
X544488D01*
X543701Y-240158D01*
X513779D01*
X506693Y-247244D01*
Y-250771D01*
X506468Y-251315D01*
Y-252031D01*
X506693Y-252575D01*
Y-254541D01*
X506348Y-254886D01*
X506074Y-255547D01*
Y-255676D01*
X505574Y-255883D01*
X505350Y-255659D01*
X504689Y-255385D01*
X503973D01*
X503346Y-255644D01*
X502720Y-255385D01*
X502004D01*
X501539Y-255578D01*
X501069Y-255107D01*
X500408Y-254834D01*
X499691D01*
X499030Y-255107D01*
X498524Y-255614D01*
X498249Y-256275D01*
Y-256992D01*
X498494Y-257581D01*
X498379Y-257875D01*
X498244Y-258081D01*
X491339D01*
Y-237402D01*
X517323Y-211417D01*
X535827D01*
Y-201540D01*
X535964Y-201334D01*
X536073Y-200787D01*
Y-198031D01*
X536073Y-198031D01*
X535964Y-197485D01*
X535827Y-197279D01*
Y-191732D01*
X546457Y-181102D01*
X574803Y-181203D01*
D02*
G37*
G36*
X478937Y-262992D02*
X476575D01*
Y-262205D01*
X478346D01*
Y-261417D01*
X478937D01*
Y-262992D01*
D02*
G37*
G36*
X337992Y-290158D02*
X335630D01*
Y-289370D01*
X337402D01*
Y-288583D01*
X337992D01*
Y-290158D01*
D02*
G37*
G36*
X319094Y-290945D02*
X316732D01*
Y-290158D01*
X318504D01*
Y-289370D01*
X319094D01*
Y-290945D01*
D02*
G37*
G36*
X238263Y-217572D02*
X238061Y-219488D01*
X236263Y-219488D01*
X192785D01*
Y-268701D01*
X236263D01*
X238061Y-268701D01*
X238263Y-270617D01*
Y-343108D01*
X38460D01*
Y-143305D01*
X238263D01*
Y-217572D01*
D02*
G37*
%LPC*%
G36*
X486849Y6610D02*
X486753D01*
Y6577D01*
X486720D01*
Y6610D01*
X482946D01*
Y6577D01*
X482784D01*
Y6545D01*
X482688D01*
Y6513D01*
X482623D01*
Y6481D01*
X482591D01*
Y6448D01*
X482559D01*
Y6416D01*
X482526D01*
Y6384D01*
X482494D01*
Y6352D01*
X482462D01*
Y6319D01*
X482430D01*
Y6287D01*
X482397D01*
Y6255D01*
X482365D01*
Y6223D01*
X482333D01*
Y6190D01*
X482301D01*
Y6158D01*
X482268D01*
Y6126D01*
X482236D01*
Y6094D01*
X482204D01*
Y6061D01*
X482171D01*
Y6029D01*
X482139D01*
Y5997D01*
X482107D01*
Y5965D01*
X482075D01*
Y5932D01*
X482042D01*
Y5900D01*
X482010D01*
Y5868D01*
X481978D01*
Y5835D01*
X481946D01*
Y5803D01*
X481913D01*
Y5771D01*
X481881D01*
Y5739D01*
X481849D01*
Y5706D01*
X481816D01*
Y5674D01*
X481784D01*
Y5642D01*
X481752D01*
Y5610D01*
X481720D01*
Y5577D01*
X481687D01*
Y5545D01*
Y5513D01*
Y5481D01*
X481655D01*
Y5448D01*
Y5416D01*
Y5384D01*
Y5352D01*
Y5319D01*
X481623D01*
Y5287D01*
Y5255D01*
Y5223D01*
Y5190D01*
Y5158D01*
Y5126D01*
Y5094D01*
Y5061D01*
Y5029D01*
Y4997D01*
Y4964D01*
Y4932D01*
Y4900D01*
Y4868D01*
Y4835D01*
Y4803D01*
Y4771D01*
Y4739D01*
Y4706D01*
Y4674D01*
Y4642D01*
Y4610D01*
Y4577D01*
Y4545D01*
Y4513D01*
Y4481D01*
Y4448D01*
Y4416D01*
Y4384D01*
Y4352D01*
Y4319D01*
Y4287D01*
Y4255D01*
Y4222D01*
Y4190D01*
Y4158D01*
Y4126D01*
Y4093D01*
Y4061D01*
Y4029D01*
Y3997D01*
Y3964D01*
Y3932D01*
Y3900D01*
Y3867D01*
Y3835D01*
Y3803D01*
Y3771D01*
Y3739D01*
Y3706D01*
Y3674D01*
Y3642D01*
Y3609D01*
Y3577D01*
Y3545D01*
Y3513D01*
Y3480D01*
Y3448D01*
Y3416D01*
Y3384D01*
Y3351D01*
Y3319D01*
Y3287D01*
Y3255D01*
Y3222D01*
Y3190D01*
Y3158D01*
Y3125D01*
Y3093D01*
Y3061D01*
Y3029D01*
Y2997D01*
Y2964D01*
Y2932D01*
Y2900D01*
Y2867D01*
Y2835D01*
Y2803D01*
Y2771D01*
Y2738D01*
Y2706D01*
Y2674D01*
Y2642D01*
Y2609D01*
Y2577D01*
Y2545D01*
Y2513D01*
Y2480D01*
Y2448D01*
Y2416D01*
Y2383D01*
Y2351D01*
Y2319D01*
Y2287D01*
Y2254D01*
Y2222D01*
Y2190D01*
Y2158D01*
Y2125D01*
Y2093D01*
Y2061D01*
Y2029D01*
Y1996D01*
Y1964D01*
Y1932D01*
Y1900D01*
Y1867D01*
Y1835D01*
Y1803D01*
Y1770D01*
Y1738D01*
Y1706D01*
Y1674D01*
Y1641D01*
Y1609D01*
Y1577D01*
Y1545D01*
Y1512D01*
Y1480D01*
Y1448D01*
Y1416D01*
Y1383D01*
Y1351D01*
Y1319D01*
Y1287D01*
Y1254D01*
Y1222D01*
Y1190D01*
Y1158D01*
Y1125D01*
Y1093D01*
Y1061D01*
Y1029D01*
Y996D01*
Y964D01*
Y932D01*
Y900D01*
Y867D01*
Y835D01*
X481655D01*
Y803D01*
Y770D01*
Y738D01*
Y706D01*
Y674D01*
X481687D01*
Y641D01*
Y609D01*
X481720D01*
Y577D01*
Y545D01*
X481752D01*
Y512D01*
X481784D01*
Y480D01*
X481816D01*
Y448D01*
X481849D01*
Y416D01*
X481881D01*
Y383D01*
X481913D01*
Y351D01*
X481946D01*
Y319D01*
X481978D01*
Y286D01*
X482010D01*
Y254D01*
X482042D01*
Y222D01*
X482075D01*
Y190D01*
X482107D01*
Y157D01*
X482139D01*
Y125D01*
X482171D01*
Y93D01*
X482204D01*
Y61D01*
X482236D01*
Y28D01*
X482268D01*
Y-4D01*
X482301D01*
Y-36D01*
X482333D01*
Y-68D01*
X482365D01*
Y-101D01*
X482397D01*
Y-133D01*
X482430D01*
Y-165D01*
X482462D01*
Y-197D01*
X482494D01*
Y-230D01*
X482526D01*
Y-262D01*
X482559D01*
Y-294D01*
X482591D01*
Y-326D01*
X482623D01*
Y-359D01*
X482688D01*
Y-391D01*
X482817D01*
Y-423D01*
X486914D01*
Y-391D01*
X486946D01*
Y-359D01*
X486978D01*
Y-326D01*
Y-294D01*
X487011D01*
Y-262D01*
Y-230D01*
Y-197D01*
Y-165D01*
Y-133D01*
Y-101D01*
Y-68D01*
Y-36D01*
Y-4D01*
Y28D01*
Y61D01*
Y93D01*
Y125D01*
Y157D01*
Y190D01*
Y222D01*
Y254D01*
Y286D01*
Y319D01*
Y351D01*
Y383D01*
Y416D01*
Y448D01*
Y480D01*
Y512D01*
Y545D01*
Y577D01*
Y609D01*
Y641D01*
Y674D01*
Y706D01*
Y738D01*
Y770D01*
Y803D01*
Y835D01*
Y867D01*
Y900D01*
Y932D01*
Y964D01*
Y996D01*
Y1029D01*
Y1061D01*
Y1093D01*
X486978D01*
Y1125D01*
Y1158D01*
X486946D01*
Y1190D01*
X486882D01*
Y1222D01*
X483430D01*
Y1254D01*
X483397D01*
Y1287D01*
Y1319D01*
Y1351D01*
Y1383D01*
Y1416D01*
Y1448D01*
Y1480D01*
Y1512D01*
Y1545D01*
Y1577D01*
Y1609D01*
Y1641D01*
Y1674D01*
Y1706D01*
Y1738D01*
Y1770D01*
Y1803D01*
Y1835D01*
Y1867D01*
Y1900D01*
Y1932D01*
Y1964D01*
Y1996D01*
Y2029D01*
Y2061D01*
Y2093D01*
Y2125D01*
Y2158D01*
Y2190D01*
Y2222D01*
Y2254D01*
Y2287D01*
Y2319D01*
Y2351D01*
X483430D01*
Y2383D01*
X486398D01*
Y2416D01*
X486462D01*
Y2448D01*
Y2480D01*
X486494D01*
Y2513D01*
Y2545D01*
Y2577D01*
Y2609D01*
Y2642D01*
Y2674D01*
Y2706D01*
Y2738D01*
Y2771D01*
Y2803D01*
Y2835D01*
Y2867D01*
Y2900D01*
Y2932D01*
Y2964D01*
Y2997D01*
Y3029D01*
Y3061D01*
Y3093D01*
Y3125D01*
Y3158D01*
Y3190D01*
Y3222D01*
Y3255D01*
Y3287D01*
Y3319D01*
Y3351D01*
Y3384D01*
Y3416D01*
Y3448D01*
Y3480D01*
Y3513D01*
Y3545D01*
Y3577D01*
Y3609D01*
Y3642D01*
Y3674D01*
X486462D01*
Y3706D01*
Y3739D01*
X486398D01*
Y3771D01*
X483430D01*
Y3803D01*
X483397D01*
Y3835D01*
Y3867D01*
Y3900D01*
Y3932D01*
Y3964D01*
Y3997D01*
Y4029D01*
Y4061D01*
Y4093D01*
Y4126D01*
Y4158D01*
Y4190D01*
Y4222D01*
Y4255D01*
Y4287D01*
Y4319D01*
Y4352D01*
Y4384D01*
Y4416D01*
Y4448D01*
Y4481D01*
Y4513D01*
Y4545D01*
Y4577D01*
Y4610D01*
Y4642D01*
Y4674D01*
Y4706D01*
Y4739D01*
Y4771D01*
Y4803D01*
Y4835D01*
Y4868D01*
Y4900D01*
Y4932D01*
X483430D01*
Y4964D01*
X486914D01*
Y4997D01*
X486946D01*
Y5029D01*
X486978D01*
Y5061D01*
X487011D01*
Y5094D01*
Y5126D01*
Y5158D01*
Y5190D01*
Y5223D01*
Y5255D01*
Y5287D01*
Y5319D01*
Y5352D01*
Y5384D01*
Y5416D01*
Y5448D01*
Y5481D01*
Y5513D01*
Y5545D01*
Y5577D01*
Y5610D01*
Y5642D01*
Y5674D01*
Y5706D01*
Y5739D01*
Y5771D01*
Y5803D01*
Y5835D01*
Y5868D01*
Y5900D01*
Y5932D01*
Y5965D01*
Y5997D01*
Y6029D01*
Y6061D01*
Y6094D01*
Y6126D01*
Y6158D01*
Y6190D01*
Y6223D01*
Y6255D01*
Y6287D01*
Y6319D01*
Y6352D01*
Y6384D01*
Y6416D01*
Y6448D01*
X486978D01*
Y6481D01*
Y6513D01*
X486946D01*
Y6545D01*
X486914D01*
Y6577D01*
X486849D01*
Y6610D01*
D02*
G37*
G36*
X470331D02*
X470267D01*
Y6577D01*
X470235D01*
Y6610D01*
X465266D01*
Y6577D01*
X465169D01*
Y6545D01*
X465137D01*
Y6513D01*
Y6481D01*
X465105D01*
Y6448D01*
Y6416D01*
Y6384D01*
Y6352D01*
Y6319D01*
Y6287D01*
Y6255D01*
Y6223D01*
Y6190D01*
Y6158D01*
Y6126D01*
Y6094D01*
Y6061D01*
Y6029D01*
Y5997D01*
Y5965D01*
Y5932D01*
Y5900D01*
Y5868D01*
Y5835D01*
Y5803D01*
Y5771D01*
Y5739D01*
Y5706D01*
Y5674D01*
Y5642D01*
Y5610D01*
Y5577D01*
Y5545D01*
Y5513D01*
Y5481D01*
Y5448D01*
Y5416D01*
Y5384D01*
Y5352D01*
Y5319D01*
Y5287D01*
Y5255D01*
Y5223D01*
Y5190D01*
Y5158D01*
Y5126D01*
Y5094D01*
Y5061D01*
Y5029D01*
Y4997D01*
X465137D01*
Y4964D01*
X465169D01*
Y4932D01*
X465202D01*
Y4900D01*
X465266D01*
Y4868D01*
X466815D01*
Y4835D01*
X466847D01*
Y4803D01*
X466879D01*
Y4771D01*
Y4739D01*
X466912D01*
Y4706D01*
Y4674D01*
Y4642D01*
Y4610D01*
Y4577D01*
Y4545D01*
Y4513D01*
Y4481D01*
Y4448D01*
Y4416D01*
Y4384D01*
Y4352D01*
Y4319D01*
Y4287D01*
Y4255D01*
Y4222D01*
Y4190D01*
Y4158D01*
Y4126D01*
Y4093D01*
Y4061D01*
Y4029D01*
Y3997D01*
Y3964D01*
Y3932D01*
Y3900D01*
Y3867D01*
Y3835D01*
Y3803D01*
Y3771D01*
Y3739D01*
Y3706D01*
Y3674D01*
Y3642D01*
Y3609D01*
Y3577D01*
Y3545D01*
Y3513D01*
Y3480D01*
Y3448D01*
Y3416D01*
Y3384D01*
Y3351D01*
Y3319D01*
Y3287D01*
Y3255D01*
Y3222D01*
Y3190D01*
Y3158D01*
Y3125D01*
Y3093D01*
Y3061D01*
Y3029D01*
Y2997D01*
Y2964D01*
Y2932D01*
Y2900D01*
Y2867D01*
Y2835D01*
Y2803D01*
Y2771D01*
Y2738D01*
Y2706D01*
Y2674D01*
Y2642D01*
Y2609D01*
Y2577D01*
Y2545D01*
Y2513D01*
Y2480D01*
Y2448D01*
Y2416D01*
Y2383D01*
Y2351D01*
Y2319D01*
Y2287D01*
Y2254D01*
Y2222D01*
Y2190D01*
Y2158D01*
Y2125D01*
Y2093D01*
Y2061D01*
Y2029D01*
Y1996D01*
Y1964D01*
Y1932D01*
Y1900D01*
Y1867D01*
Y1835D01*
Y1803D01*
Y1770D01*
Y1738D01*
Y1706D01*
Y1674D01*
Y1641D01*
Y1609D01*
Y1577D01*
Y1545D01*
Y1512D01*
Y1480D01*
Y1448D01*
Y1416D01*
Y1383D01*
Y1351D01*
Y1319D01*
Y1287D01*
Y1254D01*
Y1222D01*
Y1190D01*
Y1158D01*
Y1125D01*
Y1093D01*
Y1061D01*
Y1029D01*
Y996D01*
Y964D01*
Y932D01*
Y900D01*
Y867D01*
Y835D01*
Y803D01*
Y770D01*
Y738D01*
Y706D01*
Y674D01*
Y641D01*
Y609D01*
Y577D01*
Y545D01*
Y512D01*
Y480D01*
Y448D01*
Y416D01*
Y383D01*
Y351D01*
Y319D01*
Y286D01*
Y254D01*
Y222D01*
Y190D01*
Y157D01*
Y125D01*
Y93D01*
Y61D01*
Y28D01*
Y-4D01*
Y-36D01*
Y-68D01*
Y-101D01*
Y-133D01*
Y-165D01*
Y-197D01*
Y-230D01*
Y-262D01*
Y-294D01*
Y-326D01*
X466944D01*
Y-359D01*
X466976D01*
Y-391D01*
X467008D01*
Y-423D01*
X468589D01*
Y-391D01*
X468621D01*
Y-359D01*
X468654D01*
Y-326D01*
Y-294D01*
Y-262D01*
X468686D01*
Y-230D01*
Y-197D01*
Y-165D01*
Y-133D01*
Y-101D01*
Y-68D01*
Y-36D01*
Y-4D01*
Y28D01*
Y61D01*
Y93D01*
Y125D01*
Y157D01*
Y190D01*
Y222D01*
Y254D01*
Y286D01*
Y319D01*
Y351D01*
Y383D01*
Y416D01*
Y448D01*
Y480D01*
Y512D01*
Y545D01*
Y577D01*
Y609D01*
Y641D01*
Y674D01*
Y706D01*
Y738D01*
Y770D01*
Y803D01*
Y835D01*
Y867D01*
Y900D01*
Y932D01*
Y964D01*
Y996D01*
Y1029D01*
Y1061D01*
Y1093D01*
Y1125D01*
Y1158D01*
Y1190D01*
Y1222D01*
Y1254D01*
Y1287D01*
Y1319D01*
Y1351D01*
Y1383D01*
Y1416D01*
Y1448D01*
Y1480D01*
Y1512D01*
Y1545D01*
Y1577D01*
Y1609D01*
Y1641D01*
Y1674D01*
Y1706D01*
Y1738D01*
Y1770D01*
Y1803D01*
Y1835D01*
Y1867D01*
Y1900D01*
Y1932D01*
Y1964D01*
Y1996D01*
Y2029D01*
Y2061D01*
Y2093D01*
Y2125D01*
Y2158D01*
Y2190D01*
Y2222D01*
Y2254D01*
Y2287D01*
Y2319D01*
Y2351D01*
Y2383D01*
Y2416D01*
Y2448D01*
Y2480D01*
Y2513D01*
Y2545D01*
Y2577D01*
Y2609D01*
Y2642D01*
Y2674D01*
Y2706D01*
Y2738D01*
Y2771D01*
Y2803D01*
Y2835D01*
Y2867D01*
Y2900D01*
Y2932D01*
Y2964D01*
Y2997D01*
Y3029D01*
Y3061D01*
Y3093D01*
Y3125D01*
Y3158D01*
Y3190D01*
Y3222D01*
Y3255D01*
Y3287D01*
Y3319D01*
Y3351D01*
Y3384D01*
Y3416D01*
Y3448D01*
Y3480D01*
Y3513D01*
Y3545D01*
Y3577D01*
Y3609D01*
Y3642D01*
Y3674D01*
Y3706D01*
Y3739D01*
Y3771D01*
Y3803D01*
Y3835D01*
Y3867D01*
Y3900D01*
Y3932D01*
Y3964D01*
Y3997D01*
Y4029D01*
Y4061D01*
Y4093D01*
Y4126D01*
Y4158D01*
Y4190D01*
Y4222D01*
Y4255D01*
Y4287D01*
Y4319D01*
Y4352D01*
Y4384D01*
Y4416D01*
Y4448D01*
Y4481D01*
Y4513D01*
Y4545D01*
Y4577D01*
Y4610D01*
Y4642D01*
Y4674D01*
Y4706D01*
Y4739D01*
Y4771D01*
Y4803D01*
X468718D01*
Y4835D01*
X468750D01*
Y4868D01*
X470299D01*
Y4900D01*
X470396D01*
Y4932D01*
X470428D01*
Y4964D01*
X470460D01*
Y4997D01*
Y5029D01*
Y5061D01*
X470493D01*
Y5094D01*
Y5126D01*
Y5158D01*
Y5190D01*
Y5223D01*
Y5255D01*
Y5287D01*
Y5319D01*
Y5352D01*
Y5384D01*
Y5416D01*
Y5448D01*
Y5481D01*
Y5513D01*
Y5545D01*
Y5577D01*
Y5610D01*
Y5642D01*
Y5674D01*
Y5706D01*
Y5739D01*
Y5771D01*
Y5803D01*
Y5835D01*
Y5868D01*
Y5900D01*
Y5932D01*
Y5965D01*
Y5997D01*
Y6029D01*
Y6061D01*
Y6094D01*
Y6126D01*
Y6158D01*
Y6190D01*
Y6223D01*
Y6255D01*
Y6287D01*
Y6319D01*
Y6352D01*
Y6384D01*
Y6416D01*
X470460D01*
Y6448D01*
Y6481D01*
Y6513D01*
X470428D01*
Y6545D01*
X470396D01*
Y6577D01*
X470331D01*
Y6610D01*
D02*
G37*
G36*
X478558D02*
X473622D01*
Y6577D01*
X473525D01*
Y6545D01*
X473493D01*
Y6513D01*
Y6481D01*
X473461D01*
Y6448D01*
Y6416D01*
Y6384D01*
Y6352D01*
Y6319D01*
Y6287D01*
Y6255D01*
Y6223D01*
Y6190D01*
Y6158D01*
Y6126D01*
Y6094D01*
Y6061D01*
Y6029D01*
Y5997D01*
Y5965D01*
Y5932D01*
Y5900D01*
Y5868D01*
Y5835D01*
Y5803D01*
Y5771D01*
Y5739D01*
Y5706D01*
Y5674D01*
Y5642D01*
Y5610D01*
Y5577D01*
Y5545D01*
Y5513D01*
Y5481D01*
Y5448D01*
Y5416D01*
Y5384D01*
Y5352D01*
Y5319D01*
Y5287D01*
Y5255D01*
Y5223D01*
Y5190D01*
Y5158D01*
Y5126D01*
Y5094D01*
Y5061D01*
Y5029D01*
Y4997D01*
Y4964D01*
Y4932D01*
Y4900D01*
Y4868D01*
Y4835D01*
Y4803D01*
Y4771D01*
Y4739D01*
Y4706D01*
Y4674D01*
Y4642D01*
Y4610D01*
Y4577D01*
Y4545D01*
Y4513D01*
Y4481D01*
Y4448D01*
Y4416D01*
Y4384D01*
Y4352D01*
Y4319D01*
Y4287D01*
Y4255D01*
Y4222D01*
Y4190D01*
Y4158D01*
Y4126D01*
Y4093D01*
Y4061D01*
Y4029D01*
Y3997D01*
Y3964D01*
Y3932D01*
Y3900D01*
Y3867D01*
Y3835D01*
Y3803D01*
Y3771D01*
Y3739D01*
Y3706D01*
Y3674D01*
Y3642D01*
Y3609D01*
Y3577D01*
Y3545D01*
Y3513D01*
Y3480D01*
Y3448D01*
Y3416D01*
Y3384D01*
Y3351D01*
Y3319D01*
Y3287D01*
Y3255D01*
Y3222D01*
Y3190D01*
Y3158D01*
Y3125D01*
Y3093D01*
Y3061D01*
Y3029D01*
Y2997D01*
Y2964D01*
Y2932D01*
Y2900D01*
Y2867D01*
Y2835D01*
Y2803D01*
Y2771D01*
Y2738D01*
Y2706D01*
Y2674D01*
Y2642D01*
Y2609D01*
Y2577D01*
Y2545D01*
Y2513D01*
Y2480D01*
Y2448D01*
Y2416D01*
Y2383D01*
Y2351D01*
Y2319D01*
Y2287D01*
Y2254D01*
Y2222D01*
Y2190D01*
Y2158D01*
Y2125D01*
Y2093D01*
Y2061D01*
Y2029D01*
Y1996D01*
Y1964D01*
Y1932D01*
Y1900D01*
Y1867D01*
Y1835D01*
Y1803D01*
Y1770D01*
Y1738D01*
Y1706D01*
Y1674D01*
Y1641D01*
Y1609D01*
Y1577D01*
Y1545D01*
Y1512D01*
Y1480D01*
Y1448D01*
Y1416D01*
Y1383D01*
Y1351D01*
Y1319D01*
Y1287D01*
Y1254D01*
Y1222D01*
Y1190D01*
Y1158D01*
Y1125D01*
Y1093D01*
Y1061D01*
Y1029D01*
Y996D01*
Y964D01*
Y932D01*
Y900D01*
Y867D01*
Y835D01*
Y803D01*
Y770D01*
Y738D01*
Y706D01*
Y674D01*
Y641D01*
Y609D01*
Y577D01*
Y545D01*
Y512D01*
Y480D01*
Y448D01*
Y416D01*
Y383D01*
Y351D01*
Y319D01*
Y286D01*
Y254D01*
Y222D01*
Y190D01*
Y157D01*
Y125D01*
Y93D01*
Y61D01*
Y28D01*
Y-4D01*
Y-36D01*
Y-68D01*
Y-101D01*
Y-133D01*
Y-165D01*
Y-197D01*
Y-230D01*
Y-262D01*
Y-294D01*
Y-326D01*
X473493D01*
Y-359D01*
Y-391D01*
X473558D01*
Y-423D01*
X475138D01*
Y-391D01*
X475171D01*
Y-359D01*
X475203D01*
Y-326D01*
Y-294D01*
X475235D01*
Y-262D01*
Y-230D01*
Y-197D01*
Y-165D01*
Y-133D01*
Y-101D01*
Y-68D01*
Y-36D01*
Y-4D01*
Y28D01*
Y61D01*
Y93D01*
Y125D01*
Y157D01*
Y190D01*
Y222D01*
Y254D01*
Y286D01*
Y319D01*
Y351D01*
Y383D01*
Y416D01*
Y448D01*
Y480D01*
Y512D01*
Y545D01*
Y577D01*
Y609D01*
Y641D01*
Y674D01*
Y706D01*
Y738D01*
Y770D01*
Y803D01*
Y835D01*
Y867D01*
Y900D01*
Y932D01*
Y964D01*
Y996D01*
Y1029D01*
Y1061D01*
Y1093D01*
Y1125D01*
Y1158D01*
Y1190D01*
Y1222D01*
Y1254D01*
Y1287D01*
Y1319D01*
Y1351D01*
Y1383D01*
Y1416D01*
Y1448D01*
Y1480D01*
Y1512D01*
Y1545D01*
Y1577D01*
Y1609D01*
Y1641D01*
Y1674D01*
Y1706D01*
Y1738D01*
Y1770D01*
Y1803D01*
Y1835D01*
Y1867D01*
Y1900D01*
Y1932D01*
Y1964D01*
Y1996D01*
Y2029D01*
Y2061D01*
Y2093D01*
Y2125D01*
Y2158D01*
Y2190D01*
Y2222D01*
Y2254D01*
Y2287D01*
Y2319D01*
Y2351D01*
Y2383D01*
Y2416D01*
Y2448D01*
Y2480D01*
Y2513D01*
Y2545D01*
Y2577D01*
Y2609D01*
Y2642D01*
Y2674D01*
Y2706D01*
Y2738D01*
Y2771D01*
Y2803D01*
Y2835D01*
Y2867D01*
Y2900D01*
Y2932D01*
Y2964D01*
Y2997D01*
Y3029D01*
Y3061D01*
Y3093D01*
Y3125D01*
Y3158D01*
Y3190D01*
Y3222D01*
Y3255D01*
Y3287D01*
Y3319D01*
Y3351D01*
Y3384D01*
Y3416D01*
Y3448D01*
Y3480D01*
Y3513D01*
Y3545D01*
Y3577D01*
Y3609D01*
Y3642D01*
Y3674D01*
Y3706D01*
Y3739D01*
Y3771D01*
Y3803D01*
Y3835D01*
Y3867D01*
Y3900D01*
Y3932D01*
Y3964D01*
Y3997D01*
Y4029D01*
Y4061D01*
Y4093D01*
Y4126D01*
Y4158D01*
Y4190D01*
Y4222D01*
Y4255D01*
Y4287D01*
Y4319D01*
Y4352D01*
Y4384D01*
Y4416D01*
Y4448D01*
Y4481D01*
Y4513D01*
Y4545D01*
Y4577D01*
Y4610D01*
Y4642D01*
Y4674D01*
Y4706D01*
Y4739D01*
Y4771D01*
Y4803D01*
Y4835D01*
Y4868D01*
X476332D01*
Y4835D01*
Y4803D01*
Y4771D01*
Y4739D01*
Y4706D01*
Y4674D01*
Y4642D01*
Y4610D01*
Y4577D01*
Y4545D01*
Y4513D01*
Y4481D01*
Y4448D01*
Y4416D01*
Y4384D01*
Y4352D01*
Y4319D01*
Y4287D01*
Y4255D01*
Y4222D01*
Y4190D01*
Y4158D01*
Y4126D01*
Y4093D01*
Y4061D01*
Y4029D01*
Y3997D01*
Y3964D01*
Y3932D01*
Y3900D01*
Y3867D01*
Y3835D01*
Y3803D01*
Y3771D01*
Y3739D01*
Y3706D01*
Y3674D01*
Y3642D01*
Y3609D01*
Y3577D01*
Y3545D01*
Y3513D01*
Y3480D01*
Y3448D01*
Y3416D01*
Y3384D01*
Y3351D01*
Y3319D01*
Y3287D01*
Y3255D01*
Y3222D01*
Y3190D01*
Y3158D01*
Y3125D01*
Y3093D01*
Y3061D01*
Y3029D01*
Y2997D01*
Y2964D01*
Y2932D01*
Y2900D01*
Y2867D01*
Y2835D01*
Y2803D01*
Y2771D01*
Y2738D01*
Y2706D01*
Y2674D01*
Y2642D01*
Y2609D01*
Y2577D01*
Y2545D01*
Y2513D01*
Y2480D01*
Y2448D01*
Y2416D01*
Y2383D01*
Y2351D01*
Y2319D01*
Y2287D01*
Y2254D01*
Y2222D01*
Y2190D01*
Y2158D01*
Y2125D01*
Y2093D01*
Y2061D01*
Y2029D01*
Y1996D01*
Y1964D01*
Y1932D01*
Y1900D01*
Y1867D01*
Y1835D01*
Y1803D01*
Y1770D01*
Y1738D01*
Y1706D01*
Y1674D01*
Y1641D01*
Y1609D01*
Y1577D01*
Y1545D01*
Y1512D01*
Y1480D01*
Y1448D01*
Y1416D01*
Y1383D01*
Y1351D01*
Y1319D01*
Y1287D01*
Y1254D01*
Y1222D01*
Y1190D01*
Y1158D01*
Y1125D01*
Y1093D01*
Y1061D01*
Y1029D01*
Y996D01*
Y964D01*
Y932D01*
Y900D01*
Y867D01*
Y835D01*
Y803D01*
Y770D01*
Y738D01*
Y706D01*
Y674D01*
Y641D01*
Y609D01*
Y577D01*
Y545D01*
Y512D01*
Y480D01*
Y448D01*
Y416D01*
Y383D01*
Y351D01*
Y319D01*
Y286D01*
Y254D01*
Y222D01*
Y190D01*
Y157D01*
Y125D01*
Y93D01*
Y61D01*
Y28D01*
Y-4D01*
Y-36D01*
Y-68D01*
Y-101D01*
Y-133D01*
Y-165D01*
Y-197D01*
Y-230D01*
Y-262D01*
Y-294D01*
X476364D01*
Y-326D01*
Y-359D01*
X476397D01*
Y-391D01*
X476461D01*
Y-423D01*
X477881D01*
Y-391D01*
X477913D01*
Y-359D01*
X477945D01*
Y-326D01*
X477977D01*
Y-294D01*
Y-262D01*
Y-230D01*
Y-197D01*
Y-165D01*
Y-133D01*
Y-101D01*
Y-68D01*
Y-36D01*
Y-4D01*
Y28D01*
Y61D01*
Y93D01*
Y125D01*
Y157D01*
Y190D01*
Y222D01*
Y254D01*
Y286D01*
Y319D01*
Y351D01*
Y383D01*
Y416D01*
Y448D01*
Y480D01*
Y512D01*
Y545D01*
Y577D01*
Y609D01*
Y641D01*
Y674D01*
Y706D01*
Y738D01*
Y770D01*
Y803D01*
Y835D01*
Y867D01*
Y900D01*
Y932D01*
Y964D01*
Y996D01*
Y1029D01*
Y1061D01*
Y1093D01*
Y1125D01*
Y1158D01*
Y1190D01*
Y1222D01*
Y1254D01*
Y1287D01*
Y1319D01*
Y1351D01*
Y1383D01*
Y1416D01*
Y1448D01*
Y1480D01*
Y1512D01*
Y1545D01*
Y1577D01*
Y1609D01*
Y1641D01*
Y1674D01*
Y1706D01*
Y1738D01*
Y1770D01*
Y1803D01*
Y1835D01*
Y1867D01*
Y1900D01*
Y1932D01*
Y1964D01*
Y1996D01*
Y2029D01*
Y2061D01*
Y2093D01*
Y2125D01*
Y2158D01*
Y2190D01*
Y2222D01*
Y2254D01*
Y2287D01*
Y2319D01*
Y2351D01*
Y2383D01*
Y2416D01*
Y2448D01*
Y2480D01*
Y2513D01*
Y2545D01*
Y2577D01*
Y2609D01*
Y2642D01*
Y2674D01*
Y2706D01*
Y2738D01*
Y2771D01*
Y2803D01*
Y2835D01*
Y2867D01*
Y2900D01*
Y2932D01*
Y2964D01*
Y2997D01*
Y3029D01*
Y3061D01*
Y3093D01*
Y3125D01*
Y3158D01*
Y3190D01*
Y3222D01*
Y3255D01*
Y3287D01*
Y3319D01*
Y3351D01*
Y3384D01*
Y3416D01*
Y3448D01*
Y3480D01*
Y3513D01*
Y3545D01*
Y3577D01*
Y3609D01*
Y3642D01*
Y3674D01*
Y3706D01*
Y3739D01*
Y3771D01*
Y3803D01*
Y3835D01*
Y3867D01*
Y3900D01*
Y3932D01*
Y3964D01*
Y3997D01*
Y4029D01*
Y4061D01*
Y4093D01*
Y4126D01*
Y4158D01*
Y4190D01*
Y4222D01*
Y4255D01*
Y4287D01*
Y4319D01*
Y4352D01*
Y4384D01*
Y4416D01*
Y4448D01*
Y4481D01*
Y4513D01*
Y4545D01*
Y4577D01*
Y4610D01*
Y4642D01*
Y4674D01*
Y4706D01*
Y4739D01*
Y4771D01*
Y4803D01*
Y4835D01*
Y4868D01*
X478429D01*
Y4900D01*
X478461D01*
Y4868D01*
X478558D01*
Y4900D01*
Y4932D01*
Y4964D01*
Y4997D01*
Y5029D01*
Y5061D01*
Y5094D01*
Y5126D01*
Y5158D01*
Y5190D01*
Y5223D01*
Y5255D01*
Y5287D01*
Y5319D01*
Y5352D01*
Y5384D01*
Y5416D01*
Y5448D01*
Y5481D01*
Y5513D01*
Y5545D01*
Y5577D01*
Y5610D01*
Y5642D01*
Y5674D01*
Y5706D01*
Y5739D01*
Y5771D01*
Y5803D01*
Y5835D01*
Y5868D01*
Y5900D01*
Y5932D01*
Y5965D01*
Y5997D01*
Y6029D01*
Y6061D01*
Y6094D01*
Y6126D01*
Y6158D01*
Y6190D01*
Y6223D01*
Y6255D01*
Y6287D01*
Y6319D01*
Y6352D01*
Y6384D01*
Y6416D01*
Y6448D01*
Y6481D01*
Y6513D01*
Y6545D01*
Y6577D01*
Y6610D01*
D02*
G37*
G36*
X472525D02*
X471041D01*
Y6577D01*
X470944D01*
Y6545D01*
Y6513D01*
X470912D01*
Y6481D01*
Y6448D01*
X470880D01*
Y6416D01*
Y6384D01*
Y6352D01*
Y6319D01*
Y6287D01*
Y6255D01*
Y6223D01*
Y6190D01*
Y6158D01*
Y6126D01*
Y6094D01*
Y6061D01*
Y6029D01*
Y5997D01*
Y5965D01*
Y5932D01*
Y5900D01*
Y5868D01*
Y5835D01*
Y5803D01*
Y5771D01*
Y5739D01*
Y5706D01*
Y5674D01*
Y5642D01*
Y5610D01*
Y5577D01*
Y5545D01*
Y5513D01*
Y5481D01*
Y5448D01*
Y5416D01*
Y5384D01*
Y5352D01*
Y5319D01*
Y5287D01*
Y5255D01*
Y5223D01*
Y5190D01*
Y5158D01*
Y5126D01*
Y5094D01*
Y5061D01*
Y5029D01*
Y4997D01*
Y4964D01*
Y4932D01*
Y4900D01*
Y4868D01*
Y4835D01*
Y4803D01*
Y4771D01*
Y4739D01*
Y4706D01*
Y4674D01*
Y4642D01*
Y4610D01*
Y4577D01*
Y4545D01*
Y4513D01*
Y4481D01*
Y4448D01*
Y4416D01*
Y4384D01*
Y4352D01*
Y4319D01*
Y4287D01*
Y4255D01*
Y4222D01*
Y4190D01*
Y4158D01*
Y4126D01*
Y4093D01*
Y4061D01*
Y4029D01*
Y3997D01*
Y3964D01*
Y3932D01*
Y3900D01*
Y3867D01*
Y3835D01*
Y3803D01*
Y3771D01*
Y3739D01*
Y3706D01*
Y3674D01*
Y3642D01*
Y3609D01*
Y3577D01*
Y3545D01*
Y3513D01*
Y3480D01*
Y3448D01*
Y3416D01*
Y3384D01*
Y3351D01*
Y3319D01*
Y3287D01*
Y3255D01*
Y3222D01*
Y3190D01*
Y3158D01*
Y3125D01*
Y3093D01*
Y3061D01*
Y3029D01*
Y2997D01*
Y2964D01*
Y2932D01*
Y2900D01*
Y2867D01*
Y2835D01*
Y2803D01*
Y2771D01*
Y2738D01*
Y2706D01*
Y2674D01*
Y2642D01*
Y2609D01*
Y2577D01*
Y2545D01*
Y2513D01*
Y2480D01*
Y2448D01*
Y2416D01*
Y2383D01*
Y2351D01*
Y2319D01*
Y2287D01*
Y2254D01*
Y2222D01*
Y2190D01*
Y2158D01*
Y2125D01*
Y2093D01*
Y2061D01*
Y2029D01*
Y1996D01*
Y1964D01*
Y1932D01*
Y1900D01*
Y1867D01*
Y1835D01*
Y1803D01*
Y1770D01*
Y1738D01*
Y1706D01*
Y1674D01*
Y1641D01*
Y1609D01*
Y1577D01*
Y1545D01*
Y1512D01*
Y1480D01*
Y1448D01*
Y1416D01*
Y1383D01*
Y1351D01*
Y1319D01*
Y1287D01*
Y1254D01*
Y1222D01*
Y1190D01*
Y1158D01*
Y1125D01*
Y1093D01*
Y1061D01*
Y1029D01*
Y996D01*
Y964D01*
Y932D01*
Y900D01*
Y867D01*
Y835D01*
Y803D01*
Y770D01*
Y738D01*
Y706D01*
Y674D01*
Y641D01*
Y609D01*
Y577D01*
Y545D01*
Y512D01*
Y480D01*
Y448D01*
Y416D01*
Y383D01*
Y351D01*
Y319D01*
Y286D01*
Y254D01*
Y222D01*
Y190D01*
Y157D01*
Y125D01*
Y93D01*
Y61D01*
Y28D01*
Y-4D01*
Y-36D01*
Y-68D01*
Y-101D01*
Y-133D01*
Y-165D01*
Y-197D01*
Y-230D01*
Y-262D01*
Y-294D01*
X470912D01*
Y-326D01*
Y-359D01*
X470944D01*
Y-391D01*
X470977D01*
Y-423D01*
X472590D01*
Y-391D01*
X472622D01*
Y-359D01*
X472654D01*
Y-326D01*
Y-294D01*
Y-262D01*
Y-230D01*
Y-197D01*
Y-165D01*
Y-133D01*
Y-101D01*
Y-68D01*
Y-36D01*
Y-4D01*
Y28D01*
Y61D01*
Y93D01*
Y125D01*
Y157D01*
Y190D01*
Y222D01*
Y254D01*
Y286D01*
Y319D01*
Y351D01*
Y383D01*
Y416D01*
Y448D01*
Y480D01*
Y512D01*
Y545D01*
Y577D01*
Y609D01*
Y641D01*
Y674D01*
Y706D01*
Y738D01*
Y770D01*
Y803D01*
Y835D01*
Y867D01*
Y900D01*
Y932D01*
Y964D01*
Y996D01*
Y1029D01*
Y1061D01*
Y1093D01*
Y1125D01*
Y1158D01*
Y1190D01*
Y1222D01*
Y1254D01*
Y1287D01*
Y1319D01*
Y1351D01*
Y1383D01*
Y1416D01*
Y1448D01*
Y1480D01*
Y1512D01*
Y1545D01*
Y1577D01*
Y1609D01*
Y1641D01*
Y1674D01*
Y1706D01*
Y1738D01*
Y1770D01*
Y1803D01*
Y1835D01*
Y1867D01*
Y1900D01*
Y1932D01*
Y1964D01*
Y1996D01*
Y2029D01*
Y2061D01*
Y2093D01*
Y2125D01*
Y2158D01*
Y2190D01*
Y2222D01*
Y2254D01*
Y2287D01*
Y2319D01*
Y2351D01*
Y2383D01*
Y2416D01*
Y2448D01*
Y2480D01*
Y2513D01*
Y2545D01*
Y2577D01*
Y2609D01*
Y2642D01*
Y2674D01*
Y2706D01*
Y2738D01*
Y2771D01*
Y2803D01*
Y2835D01*
Y2867D01*
Y2900D01*
Y2932D01*
Y2964D01*
Y2997D01*
Y3029D01*
Y3061D01*
Y3093D01*
Y3125D01*
Y3158D01*
Y3190D01*
Y3222D01*
Y3255D01*
Y3287D01*
Y3319D01*
Y3351D01*
Y3384D01*
Y3416D01*
Y3448D01*
Y3480D01*
Y3513D01*
Y3545D01*
Y3577D01*
Y3609D01*
Y3642D01*
Y3674D01*
Y3706D01*
Y3739D01*
Y3771D01*
Y3803D01*
Y3835D01*
Y3867D01*
Y3900D01*
Y3932D01*
Y3964D01*
Y3997D01*
Y4029D01*
Y4061D01*
Y4093D01*
Y4126D01*
Y4158D01*
Y4190D01*
Y4222D01*
Y4255D01*
Y4287D01*
Y4319D01*
Y4352D01*
Y4384D01*
Y4416D01*
Y4448D01*
Y4481D01*
Y4513D01*
Y4545D01*
Y4577D01*
Y4610D01*
Y4642D01*
Y4674D01*
Y4706D01*
Y4739D01*
Y4771D01*
Y4803D01*
Y4835D01*
Y4868D01*
Y4900D01*
Y4932D01*
Y4964D01*
Y4997D01*
Y5029D01*
Y5061D01*
Y5094D01*
Y5126D01*
Y5158D01*
Y5190D01*
Y5223D01*
Y5255D01*
Y5287D01*
Y5319D01*
Y5352D01*
Y5384D01*
Y5416D01*
Y5448D01*
Y5481D01*
Y5513D01*
Y5545D01*
Y5577D01*
Y5610D01*
Y5642D01*
Y5674D01*
Y5706D01*
Y5739D01*
Y5771D01*
Y5803D01*
Y5835D01*
Y5868D01*
Y5900D01*
Y5932D01*
Y5965D01*
Y5997D01*
Y6029D01*
Y6061D01*
Y6094D01*
Y6126D01*
Y6158D01*
Y6190D01*
Y6223D01*
Y6255D01*
Y6287D01*
Y6319D01*
Y6352D01*
Y6384D01*
Y6416D01*
Y6448D01*
Y6481D01*
Y6513D01*
X472622D01*
Y6545D01*
X472590D01*
Y6577D01*
X472525D01*
Y6610D01*
D02*
G37*
G36*
X480784Y11804D02*
X479591D01*
Y11772D01*
X479107D01*
Y11739D01*
X478784D01*
Y11707D01*
X478526D01*
Y11675D01*
X478332D01*
Y11643D01*
X478106D01*
Y11610D01*
X477913D01*
Y11578D01*
X477752D01*
Y11546D01*
X477590D01*
Y11514D01*
X477429D01*
Y11481D01*
X477300D01*
Y11449D01*
X477171D01*
Y11417D01*
X477042D01*
Y11384D01*
X476913D01*
Y11352D01*
X476816D01*
Y11320D01*
X476687D01*
Y11288D01*
X476590D01*
Y11255D01*
X476493D01*
Y11223D01*
X476364D01*
Y11191D01*
X476267D01*
Y11159D01*
X476171D01*
Y11126D01*
X476074D01*
Y11094D01*
X476009D01*
Y11062D01*
X475913D01*
Y11030D01*
X475816D01*
Y10997D01*
X475719D01*
Y10965D01*
X475655D01*
Y10933D01*
X475558D01*
Y10901D01*
X475493D01*
Y10868D01*
X475396D01*
Y10836D01*
X475332D01*
Y10804D01*
X475267D01*
Y10772D01*
X475171D01*
Y10739D01*
X475106D01*
Y10707D01*
X475042D01*
Y10675D01*
X474977D01*
Y10643D01*
X474880D01*
Y10610D01*
X474816D01*
Y10578D01*
X474751D01*
Y10546D01*
X474687D01*
Y10514D01*
X474622D01*
Y10481D01*
X474558D01*
Y10449D01*
X474493D01*
Y10417D01*
X474429D01*
Y10384D01*
X474364D01*
Y10352D01*
X474299D01*
Y10320D01*
X474267D01*
Y10288D01*
X474203D01*
Y10255D01*
X474138D01*
Y10223D01*
X474074D01*
Y10191D01*
X474009D01*
Y10159D01*
X473977D01*
Y10126D01*
X473912D01*
Y10094D01*
X473848D01*
Y10062D01*
X473816D01*
Y10029D01*
X473751D01*
Y9997D01*
X473687D01*
Y9965D01*
X473654D01*
Y9933D01*
X473590D01*
Y9900D01*
X473525D01*
Y9868D01*
X473493D01*
Y9836D01*
X473428D01*
Y9804D01*
X473396D01*
Y9771D01*
X473332D01*
Y9739D01*
X473299D01*
Y9707D01*
X473235D01*
Y9675D01*
X473203D01*
Y9642D01*
X473138D01*
Y9610D01*
X473106D01*
Y9578D01*
X473041D01*
Y9546D01*
X473009D01*
Y9513D01*
X472977D01*
Y9481D01*
X472912D01*
Y9449D01*
X472880D01*
Y9417D01*
X472816D01*
Y9384D01*
X472783D01*
Y9352D01*
X472751D01*
Y9320D01*
X472686D01*
Y9287D01*
X472654D01*
Y9255D01*
X472622D01*
Y9223D01*
X472557D01*
Y9191D01*
X472525D01*
Y9159D01*
X472493D01*
Y9126D01*
X472461D01*
Y9094D01*
X472396D01*
Y9062D01*
X472364D01*
Y9029D01*
X472332D01*
Y8997D01*
X472299D01*
Y8965D01*
X472235D01*
Y8933D01*
X472202D01*
Y8900D01*
X472170D01*
Y8868D01*
X472138D01*
Y8836D01*
X472106D01*
Y8804D01*
X472041D01*
Y8771D01*
X472009D01*
Y8739D01*
X471977D01*
Y8707D01*
X471944D01*
Y8675D01*
X471912D01*
Y8642D01*
X471880D01*
Y8610D01*
X471848D01*
Y8578D01*
X471815D01*
Y8546D01*
X471751D01*
Y8513D01*
X471719D01*
Y8481D01*
X471686D01*
Y8449D01*
X471654D01*
Y8416D01*
X471622D01*
Y8384D01*
X471590D01*
Y8352D01*
X471557D01*
Y8320D01*
X471525D01*
Y8287D01*
X471493D01*
Y8255D01*
X471460D01*
Y8223D01*
X471428D01*
Y8191D01*
X471396D01*
Y8158D01*
X471364D01*
Y8126D01*
X471332D01*
Y8094D01*
X471299D01*
Y8062D01*
X471267D01*
Y8029D01*
X471235D01*
Y7997D01*
X471202D01*
Y7965D01*
X471170D01*
Y7932D01*
X471138D01*
Y7900D01*
X471106D01*
Y7868D01*
X471073D01*
Y7836D01*
X471041D01*
Y7803D01*
X471009D01*
Y7771D01*
X470977D01*
Y7739D01*
Y7707D01*
X470944D01*
Y7674D01*
X470912D01*
Y7642D01*
X470880D01*
Y7610D01*
X470848D01*
Y7578D01*
X470815D01*
Y7545D01*
X470783D01*
Y7513D01*
X470751D01*
Y7481D01*
X470718D01*
Y7449D01*
Y7416D01*
X470686D01*
Y7384D01*
X470654D01*
Y7352D01*
X470622D01*
Y7320D01*
X470589D01*
Y7287D01*
X470557D01*
Y7255D01*
Y7223D01*
X470525D01*
Y7191D01*
X470493D01*
Y7158D01*
X470460D01*
Y7126D01*
X470977D01*
Y7158D01*
X471009D01*
Y7191D01*
X471041D01*
Y7223D01*
Y7255D01*
X471073D01*
Y7287D01*
X471106D01*
Y7320D01*
X471138D01*
Y7352D01*
X471170D01*
Y7384D01*
X471202D01*
Y7416D01*
X471235D01*
Y7449D01*
X471267D01*
Y7481D01*
X471299D01*
Y7513D01*
Y7545D01*
X471332D01*
Y7578D01*
X471364D01*
Y7610D01*
X471396D01*
Y7642D01*
X471428D01*
Y7674D01*
X471460D01*
Y7707D01*
X471493D01*
Y7739D01*
X471525D01*
Y7771D01*
X471557D01*
Y7803D01*
X471590D01*
Y7836D01*
X471622D01*
Y7868D01*
X471654D01*
Y7900D01*
X471686D01*
Y7932D01*
X471719D01*
Y7965D01*
X471751D01*
Y7997D01*
X471783D01*
Y8029D01*
X471815D01*
Y8062D01*
X471848D01*
Y8094D01*
X471880D01*
Y8126D01*
X471912D01*
Y8158D01*
X471944D01*
Y8191D01*
X472009D01*
Y8223D01*
X472041D01*
Y8255D01*
X472074D01*
Y8287D01*
X472106D01*
Y8320D01*
X472138D01*
Y8352D01*
X472170D01*
Y8384D01*
X472202D01*
Y8416D01*
X472235D01*
Y8449D01*
X472267D01*
Y8481D01*
X472332D01*
Y8513D01*
X472364D01*
Y8546D01*
X472396D01*
Y8578D01*
X472428D01*
Y8610D01*
X472461D01*
Y8642D01*
X472525D01*
Y8675D01*
X472557D01*
Y8707D01*
X472590D01*
Y8739D01*
X472622D01*
Y8771D01*
X472686D01*
Y8804D01*
X472719D01*
Y8836D01*
X472751D01*
Y8868D01*
X472783D01*
Y8900D01*
X472848D01*
Y8933D01*
X472880D01*
Y8965D01*
X472912D01*
Y8997D01*
X472977D01*
Y9029D01*
X473009D01*
Y9062D01*
X473041D01*
Y9094D01*
X473106D01*
Y9126D01*
X473138D01*
Y9159D01*
X473170D01*
Y9191D01*
X473235D01*
Y9223D01*
X473267D01*
Y9255D01*
X473332D01*
Y9287D01*
X473364D01*
Y9320D01*
X473428D01*
Y9352D01*
X473461D01*
Y9384D01*
X473525D01*
Y9417D01*
X473558D01*
Y9449D01*
X473622D01*
Y9481D01*
X473654D01*
Y9513D01*
X473719D01*
Y9546D01*
X473751D01*
Y9578D01*
X473816D01*
Y9610D01*
X473880D01*
Y9642D01*
X473912D01*
Y9675D01*
X473977D01*
Y9707D01*
X474041D01*
Y9739D01*
X474074D01*
Y9771D01*
X474138D01*
Y9804D01*
X474203D01*
Y9836D01*
X474235D01*
Y9868D01*
X474299D01*
Y9900D01*
X474364D01*
Y9933D01*
X474429D01*
Y9965D01*
X474493D01*
Y9997D01*
X474558D01*
Y10029D01*
X474622D01*
Y10062D01*
X474654D01*
Y10094D01*
X474719D01*
Y10126D01*
X474784D01*
Y10159D01*
X474848D01*
Y10191D01*
X474913D01*
Y10223D01*
X475009D01*
Y10255D01*
X475074D01*
Y10288D01*
X475138D01*
Y10320D01*
X475203D01*
Y10352D01*
X475267D01*
Y10384D01*
X475332D01*
Y10417D01*
X475429D01*
Y10449D01*
X475493D01*
Y10481D01*
X475558D01*
Y10514D01*
X475655D01*
Y10546D01*
X475719D01*
Y10578D01*
X475816D01*
Y10610D01*
X475913D01*
Y10643D01*
X475977D01*
Y10675D01*
X476074D01*
Y10707D01*
X476171D01*
Y10739D01*
X476267D01*
Y10772D01*
X476332D01*
Y10804D01*
X476461D01*
Y10836D01*
X476558D01*
Y10868D01*
X476655D01*
Y10901D01*
X476751D01*
Y10933D01*
X476881D01*
Y10965D01*
X476977D01*
Y10997D01*
X477106D01*
Y11030D01*
X477235D01*
Y11062D01*
X477364D01*
Y11094D01*
X477493D01*
Y11126D01*
X477655D01*
Y11159D01*
X477816D01*
Y11191D01*
X477945D01*
Y11223D01*
X478171D01*
Y11255D01*
X478365D01*
Y11288D01*
X478590D01*
Y11320D01*
X478849D01*
Y11352D01*
X479203D01*
Y11384D01*
X479784D01*
Y11417D01*
X480591D01*
Y11384D01*
X480623D01*
Y11417D01*
X480655D01*
Y11384D01*
X481171D01*
Y11352D01*
X481526D01*
Y11320D01*
X481816D01*
Y11288D01*
X482010D01*
Y11255D01*
X482204D01*
Y11223D01*
X482397D01*
Y11191D01*
X482559D01*
Y11159D01*
X482720D01*
Y11126D01*
X482881D01*
Y11094D01*
X483010D01*
Y11062D01*
X483139D01*
Y11030D01*
X483268D01*
Y10997D01*
X483397D01*
Y10965D01*
X483494D01*
Y10933D01*
X483623D01*
Y10901D01*
X483720D01*
Y10868D01*
X483817D01*
Y10836D01*
X483914D01*
Y10804D01*
X484010D01*
Y10772D01*
X484107D01*
Y10739D01*
X484204D01*
Y10707D01*
X484301D01*
Y10675D01*
X484398D01*
Y10643D01*
X484462D01*
Y10610D01*
X484559D01*
Y10578D01*
X484623D01*
Y10546D01*
X484720D01*
Y10514D01*
X484785D01*
Y10481D01*
X484881D01*
Y10449D01*
X484946D01*
Y10417D01*
X485010D01*
Y10384D01*
X485107D01*
Y10352D01*
X485172D01*
Y10320D01*
X485236D01*
Y10288D01*
X485301D01*
Y10255D01*
X485365D01*
Y10223D01*
X485462D01*
Y10191D01*
X485527D01*
Y10159D01*
X485559D01*
Y10126D01*
X485623D01*
Y10094D01*
X485688D01*
Y10062D01*
X485752D01*
Y10029D01*
X485817D01*
Y9997D01*
X485882D01*
Y9965D01*
X485946D01*
Y9933D01*
X486011D01*
Y9900D01*
X486075D01*
Y9868D01*
X486107D01*
Y9836D01*
X486172D01*
Y9804D01*
X486236D01*
Y9771D01*
X486301D01*
Y9739D01*
X486333D01*
Y9707D01*
X486398D01*
Y9675D01*
X486462D01*
Y9642D01*
X486494D01*
Y9610D01*
X486559D01*
Y9578D01*
X486623D01*
Y9546D01*
X486656D01*
Y9513D01*
X486720D01*
Y9481D01*
X486753D01*
Y9449D01*
X486817D01*
Y9417D01*
X486849D01*
Y9384D01*
X486914D01*
Y9352D01*
X486946D01*
Y9320D01*
X487011D01*
Y9287D01*
X487043D01*
Y9255D01*
X487108D01*
Y9223D01*
X487140D01*
Y9191D01*
X487172D01*
Y9159D01*
X487236D01*
Y9126D01*
X487269D01*
Y9094D01*
X487333D01*
Y9062D01*
X487366D01*
Y9029D01*
X487398D01*
Y8997D01*
X487462D01*
Y8965D01*
X487495D01*
Y8933D01*
X487527D01*
Y8900D01*
X487591D01*
Y8868D01*
X487624D01*
Y8836D01*
X487656D01*
Y8804D01*
X487688D01*
Y8771D01*
X487753D01*
Y8739D01*
X487785D01*
Y8707D01*
X487817D01*
Y8675D01*
X487850D01*
Y8642D01*
X487914D01*
Y8610D01*
X487946D01*
Y8578D01*
X487979D01*
Y8546D01*
X488011D01*
Y8513D01*
X488043D01*
Y8481D01*
X488075D01*
Y8449D01*
X488140D01*
Y8416D01*
X488172D01*
Y8384D01*
X488204D01*
Y8352D01*
X488237D01*
Y8320D01*
X488269D01*
Y8287D01*
X488301D01*
Y8255D01*
X488333D01*
Y8223D01*
X488366D01*
Y8191D01*
X488398D01*
Y8158D01*
X488462D01*
Y8126D01*
X488495D01*
Y8094D01*
X488527D01*
Y8062D01*
X488559D01*
Y8029D01*
X488591D01*
Y7997D01*
X488624D01*
Y7965D01*
X488656D01*
Y7932D01*
X488688D01*
Y7900D01*
X488721D01*
Y7868D01*
X488753D01*
Y7836D01*
X488785D01*
Y7803D01*
X488817D01*
Y7771D01*
X488850D01*
Y7739D01*
X488882D01*
Y7707D01*
X488914D01*
Y7674D01*
X488946D01*
Y7642D01*
X488979D01*
Y7610D01*
X489011D01*
Y7578D01*
Y7545D01*
X489043D01*
Y7513D01*
X489076D01*
Y7481D01*
X489108D01*
Y7449D01*
X489140D01*
Y7416D01*
X489172D01*
Y7384D01*
X489205D01*
Y7352D01*
X489237D01*
Y7320D01*
X489269D01*
Y7287D01*
X489301D01*
Y7255D01*
Y7223D01*
X489333D01*
Y7191D01*
X489366D01*
Y7158D01*
X489398D01*
Y7126D01*
X489430D01*
Y7094D01*
X489463D01*
Y7062D01*
X489495D01*
Y7029D01*
Y6997D01*
X489527D01*
Y6965D01*
X489559D01*
Y6932D01*
X489592D01*
Y6900D01*
X489624D01*
Y6868D01*
Y6836D01*
X489656D01*
Y6803D01*
X489688D01*
Y6771D01*
X489721D01*
Y6739D01*
X489753D01*
Y6707D01*
Y6674D01*
X489785D01*
Y6642D01*
X489817D01*
Y6610D01*
X489850D01*
Y6577D01*
Y6545D01*
X489882D01*
Y6513D01*
X489914D01*
Y6481D01*
X489947D01*
Y6448D01*
Y6416D01*
X489979D01*
Y6384D01*
X490011D01*
Y6352D01*
Y6319D01*
X490043D01*
Y6287D01*
X490076D01*
Y6255D01*
X490108D01*
Y6223D01*
Y6190D01*
X490140D01*
Y6158D01*
X490172D01*
Y6126D01*
Y6094D01*
X490205D01*
Y6061D01*
X490237D01*
Y6029D01*
Y5997D01*
X490269D01*
Y5965D01*
X490301D01*
Y5932D01*
Y5900D01*
X490334D01*
Y5868D01*
X490366D01*
Y5835D01*
Y5803D01*
X490398D01*
Y5771D01*
X490430D01*
Y5739D01*
Y5706D01*
X490463D01*
Y5674D01*
Y5642D01*
X490495D01*
Y5610D01*
X490527D01*
Y5577D01*
Y5545D01*
X490559D01*
Y5513D01*
Y5481D01*
X490592D01*
Y5448D01*
X490624D01*
Y5416D01*
Y5384D01*
X490656D01*
Y5352D01*
Y5319D01*
X490689D01*
Y5287D01*
Y5255D01*
X490721D01*
Y5223D01*
X490753D01*
Y5190D01*
Y5158D01*
X490785D01*
Y5126D01*
Y5094D01*
X490818D01*
Y5061D01*
Y5029D01*
X490850D01*
Y4997D01*
Y4964D01*
X490882D01*
Y4932D01*
Y4900D01*
X490914D01*
Y4868D01*
X490947D01*
Y4835D01*
Y4803D01*
X490979D01*
Y4771D01*
Y4739D01*
X491011D01*
Y4706D01*
Y4674D01*
X491043D01*
Y4642D01*
Y4610D01*
X491076D01*
Y4577D01*
Y4545D01*
Y4513D01*
X491108D01*
Y4481D01*
Y4448D01*
X491140D01*
Y4416D01*
Y4384D01*
X491173D01*
Y4352D01*
Y4319D01*
X491205D01*
Y4287D01*
Y4255D01*
X491237D01*
Y4222D01*
Y4190D01*
X491269D01*
Y4158D01*
Y4126D01*
Y4093D01*
X491301D01*
Y4061D01*
Y4029D01*
X491334D01*
Y3997D01*
Y3964D01*
X491366D01*
Y3932D01*
Y3900D01*
Y3867D01*
X491398D01*
Y3835D01*
Y3803D01*
X491431D01*
Y3771D01*
Y3739D01*
Y3706D01*
X491463D01*
Y3674D01*
Y3642D01*
X491495D01*
Y3609D01*
Y3577D01*
Y3545D01*
X491527D01*
Y3513D01*
Y3480D01*
Y3448D01*
X491560D01*
Y3416D01*
Y3384D01*
Y3351D01*
X491592D01*
Y3319D01*
Y3287D01*
X491624D01*
Y3255D01*
Y3222D01*
Y3190D01*
X491656D01*
Y3158D01*
Y3125D01*
Y3093D01*
X491689D01*
Y3061D01*
Y3029D01*
Y2997D01*
Y2964D01*
X491721D01*
Y2932D01*
Y2900D01*
Y2867D01*
X491753D01*
Y2835D01*
Y2803D01*
Y2771D01*
X491785D01*
Y2738D01*
Y2706D01*
Y2674D01*
Y2642D01*
X491818D01*
Y2609D01*
Y2577D01*
Y2545D01*
X491850D01*
Y2513D01*
Y2480D01*
Y2448D01*
Y2416D01*
X491882D01*
Y2383D01*
Y2351D01*
Y2319D01*
Y2287D01*
X491915D01*
Y2254D01*
Y2222D01*
Y2190D01*
Y2158D01*
X491947D01*
Y2125D01*
Y2093D01*
Y2061D01*
Y2029D01*
X491979D01*
Y1996D01*
Y1964D01*
Y1932D01*
Y1900D01*
Y1867D01*
X492011D01*
Y1835D01*
Y1803D01*
Y1770D01*
Y1738D01*
X492043D01*
Y1706D01*
Y1674D01*
Y1641D01*
Y1609D01*
Y1577D01*
Y1545D01*
X492076D01*
Y1512D01*
Y1480D01*
Y1448D01*
Y1416D01*
Y1383D01*
X492108D01*
Y1351D01*
Y1319D01*
Y1287D01*
Y1254D01*
Y1222D01*
Y1190D01*
X492140D01*
Y1158D01*
Y1125D01*
Y1093D01*
Y1061D01*
Y1029D01*
Y996D01*
Y964D01*
X492173D01*
Y932D01*
Y900D01*
Y867D01*
Y835D01*
Y803D01*
Y770D01*
Y738D01*
Y706D01*
Y674D01*
X492205D01*
Y641D01*
Y609D01*
Y577D01*
Y545D01*
Y512D01*
Y480D01*
Y448D01*
Y416D01*
Y383D01*
X492237D01*
Y351D01*
Y319D01*
Y286D01*
Y254D01*
Y222D01*
Y190D01*
Y157D01*
Y125D01*
Y93D01*
Y61D01*
Y28D01*
Y-4D01*
Y-36D01*
Y-68D01*
Y-101D01*
Y-133D01*
Y-165D01*
X492269D01*
Y-197D01*
Y-230D01*
Y-262D01*
Y-294D01*
Y-326D01*
Y-359D01*
Y-391D01*
Y-423D01*
Y-455D01*
Y-488D01*
Y-520D01*
X492657D01*
Y-488D01*
Y-455D01*
Y-423D01*
Y-391D01*
Y-359D01*
Y-326D01*
Y-294D01*
Y-262D01*
Y-230D01*
Y-197D01*
Y-165D01*
Y-133D01*
X492624D01*
Y-101D01*
X492657D01*
Y-68D01*
Y-36D01*
Y-4D01*
X492624D01*
Y28D01*
Y61D01*
Y93D01*
Y125D01*
Y157D01*
Y190D01*
Y222D01*
Y254D01*
Y286D01*
Y319D01*
Y351D01*
Y383D01*
Y416D01*
Y448D01*
X492592D01*
Y480D01*
Y512D01*
Y545D01*
Y577D01*
Y609D01*
Y641D01*
Y674D01*
Y706D01*
Y738D01*
Y770D01*
X492560D01*
Y803D01*
Y835D01*
Y867D01*
Y900D01*
Y932D01*
Y964D01*
Y996D01*
Y1029D01*
X492527D01*
Y1061D01*
Y1093D01*
Y1125D01*
Y1158D01*
Y1190D01*
Y1222D01*
Y1254D01*
X492495D01*
Y1287D01*
Y1319D01*
Y1351D01*
Y1383D01*
Y1416D01*
Y1448D01*
X492463D01*
Y1480D01*
Y1512D01*
Y1545D01*
Y1577D01*
Y1609D01*
X492431D01*
Y1641D01*
Y1674D01*
Y1706D01*
Y1738D01*
Y1770D01*
X492398D01*
Y1803D01*
Y1835D01*
Y1867D01*
Y1900D01*
Y1932D01*
X492366D01*
Y1964D01*
Y1996D01*
Y2029D01*
Y2061D01*
Y2093D01*
X492334D01*
Y2125D01*
Y2158D01*
Y2190D01*
Y2222D01*
X492302D01*
Y2254D01*
Y2287D01*
Y2319D01*
Y2351D01*
X492269D01*
Y2383D01*
Y2416D01*
Y2448D01*
Y2480D01*
X492237D01*
Y2513D01*
Y2545D01*
Y2577D01*
Y2609D01*
X492205D01*
Y2642D01*
Y2674D01*
Y2706D01*
X492173D01*
Y2738D01*
Y2771D01*
Y2803D01*
Y2835D01*
X492140D01*
Y2867D01*
Y2900D01*
Y2932D01*
X492108D01*
Y2964D01*
Y2997D01*
Y3029D01*
Y3061D01*
X492076D01*
Y3093D01*
Y3125D01*
Y3158D01*
X492043D01*
Y3190D01*
Y3222D01*
Y3255D01*
X492011D01*
Y3287D01*
Y3319D01*
Y3351D01*
X491979D01*
Y3384D01*
Y3416D01*
Y3448D01*
X491947D01*
Y3480D01*
Y3513D01*
Y3545D01*
X491915D01*
Y3577D01*
Y3609D01*
X491882D01*
Y3642D01*
Y3674D01*
Y3706D01*
X491850D01*
Y3739D01*
Y3771D01*
Y3803D01*
X491818D01*
Y3835D01*
Y3867D01*
X491785D01*
Y3900D01*
Y3932D01*
Y3964D01*
X491753D01*
Y3997D01*
Y4029D01*
X491721D01*
Y4061D01*
Y4093D01*
Y4126D01*
X491689D01*
Y4158D01*
Y4190D01*
X491656D01*
Y4222D01*
Y4255D01*
X491624D01*
Y4287D01*
Y4319D01*
Y4352D01*
X491592D01*
Y4384D01*
Y4416D01*
X491560D01*
Y4448D01*
Y4481D01*
X491527D01*
Y4513D01*
Y4545D01*
X491495D01*
Y4577D01*
Y4610D01*
Y4642D01*
X491463D01*
Y4674D01*
Y4706D01*
X491431D01*
Y4739D01*
Y4771D01*
X491398D01*
Y4803D01*
Y4835D01*
X491366D01*
Y4868D01*
Y4900D01*
X491334D01*
Y4932D01*
Y4964D01*
X491301D01*
Y4997D01*
Y5029D01*
X491269D01*
Y5061D01*
Y5094D01*
X491237D01*
Y5126D01*
Y5158D01*
X491205D01*
Y5190D01*
Y5223D01*
X491173D01*
Y5255D01*
X491140D01*
Y5287D01*
Y5319D01*
X491108D01*
Y5352D01*
Y5384D01*
X491076D01*
Y5416D01*
Y5448D01*
X491043D01*
Y5481D01*
Y5513D01*
X491011D01*
Y5545D01*
X490979D01*
Y5577D01*
Y5610D01*
X490947D01*
Y5642D01*
Y5674D01*
X490914D01*
Y5706D01*
X490882D01*
Y5739D01*
Y5771D01*
X490850D01*
Y5803D01*
Y5835D01*
X490818D01*
Y5868D01*
X490785D01*
Y5900D01*
Y5932D01*
X490753D01*
Y5965D01*
Y5997D01*
X490721D01*
Y6029D01*
X490689D01*
Y6061D01*
Y6094D01*
X490656D01*
Y6126D01*
X490624D01*
Y6158D01*
Y6190D01*
X490592D01*
Y6223D01*
X490559D01*
Y6255D01*
Y6287D01*
X490527D01*
Y6319D01*
X490495D01*
Y6352D01*
Y6384D01*
X490463D01*
Y6416D01*
X490430D01*
Y6448D01*
Y6481D01*
X490398D01*
Y6513D01*
X490366D01*
Y6545D01*
X490334D01*
Y6577D01*
Y6610D01*
X490301D01*
Y6642D01*
X490269D01*
Y6674D01*
Y6707D01*
X490237D01*
Y6739D01*
X490205D01*
Y6771D01*
X490172D01*
Y6803D01*
Y6836D01*
X490140D01*
Y6868D01*
X490108D01*
Y6900D01*
X490076D01*
Y6932D01*
X490043D01*
Y6965D01*
Y6997D01*
X490011D01*
Y7029D01*
X489979D01*
Y7062D01*
X489947D01*
Y7094D01*
Y7126D01*
X489914D01*
Y7158D01*
X489882D01*
Y7191D01*
X489850D01*
Y7223D01*
X489817D01*
Y7255D01*
X489785D01*
Y7287D01*
Y7320D01*
X489753D01*
Y7352D01*
X489721D01*
Y7384D01*
X489688D01*
Y7416D01*
X489656D01*
Y7449D01*
X489624D01*
Y7481D01*
Y7513D01*
X489592D01*
Y7545D01*
X489559D01*
Y7578D01*
X489527D01*
Y7610D01*
X489495D01*
Y7642D01*
X489463D01*
Y7674D01*
X489430D01*
Y7707D01*
X489398D01*
Y7739D01*
X489366D01*
Y7771D01*
Y7803D01*
X489333D01*
Y7836D01*
X489301D01*
Y7868D01*
X489269D01*
Y7900D01*
X489237D01*
Y7932D01*
X489205D01*
Y7965D01*
X489172D01*
Y7997D01*
X489140D01*
Y8029D01*
X489108D01*
Y8062D01*
X489076D01*
Y8094D01*
X489043D01*
Y8126D01*
X489011D01*
Y8158D01*
X488979D01*
Y8191D01*
X488946D01*
Y8223D01*
X488914D01*
Y8255D01*
X488882D01*
Y8287D01*
X488850D01*
Y8320D01*
X488817D01*
Y8352D01*
X488785D01*
Y8384D01*
X488753D01*
Y8416D01*
X488721D01*
Y8449D01*
X488688D01*
Y8481D01*
X488624D01*
Y8513D01*
X488591D01*
Y8546D01*
X488559D01*
Y8578D01*
X488527D01*
Y8610D01*
X488495D01*
Y8642D01*
X488462D01*
Y8675D01*
X488430D01*
Y8707D01*
X488398D01*
Y8739D01*
X488366D01*
Y8771D01*
X488301D01*
Y8804D01*
X488269D01*
Y8836D01*
X488237D01*
Y8868D01*
X488204D01*
Y8900D01*
X488172D01*
Y8933D01*
X488108D01*
Y8965D01*
X488075D01*
Y8997D01*
X488043D01*
Y9029D01*
X488011D01*
Y9062D01*
X487979D01*
Y9094D01*
X487914D01*
Y9126D01*
X487882D01*
Y9159D01*
X487850D01*
Y9191D01*
X487785D01*
Y9223D01*
X487753D01*
Y9255D01*
X487720D01*
Y9287D01*
X487688D01*
Y9320D01*
X487624D01*
Y9352D01*
X487591D01*
Y9384D01*
X487527D01*
Y9417D01*
X487495D01*
Y9449D01*
X487462D01*
Y9481D01*
X487398D01*
Y9513D01*
X487366D01*
Y9546D01*
X487333D01*
Y9578D01*
X487269D01*
Y9610D01*
X487236D01*
Y9642D01*
X487172D01*
Y9675D01*
X487140D01*
Y9707D01*
X487075D01*
Y9739D01*
X487043D01*
Y9771D01*
X486978D01*
Y9804D01*
X486946D01*
Y9836D01*
X486882D01*
Y9868D01*
X486817D01*
Y9900D01*
X486785D01*
Y9933D01*
X486720D01*
Y9965D01*
X486688D01*
Y9997D01*
X486623D01*
Y10029D01*
X486559D01*
Y10062D01*
X486527D01*
Y10094D01*
X486462D01*
Y10126D01*
X486398D01*
Y10159D01*
X486333D01*
Y10191D01*
X486301D01*
Y10223D01*
X486236D01*
Y10255D01*
X486172D01*
Y10288D01*
X486107D01*
Y10320D01*
X486043D01*
Y10352D01*
X486011D01*
Y10384D01*
X485914D01*
Y10417D01*
X485882D01*
Y10449D01*
X485817D01*
Y10481D01*
X485720D01*
Y10514D01*
X485656D01*
Y10546D01*
X485623D01*
Y10578D01*
X485559D01*
Y10610D01*
X485462D01*
Y10643D01*
X485398D01*
Y10675D01*
X485333D01*
Y10707D01*
X485269D01*
Y10739D01*
X485204D01*
Y10772D01*
X485107D01*
Y10804D01*
X485043D01*
Y10836D01*
X484978D01*
Y10868D01*
X484881D01*
Y10901D01*
X484817D01*
Y10933D01*
X484720D01*
Y10965D01*
X484623D01*
Y10997D01*
X484559D01*
Y11030D01*
X484462D01*
Y11062D01*
X484365D01*
Y11094D01*
X484268D01*
Y11126D01*
X484204D01*
Y11159D01*
X484107D01*
Y11191D01*
X484010D01*
Y11223D01*
X483881D01*
Y11255D01*
X483784D01*
Y11288D01*
X483688D01*
Y11320D01*
X483559D01*
Y11352D01*
X483462D01*
Y11384D01*
X483333D01*
Y11417D01*
X483204D01*
Y11449D01*
X483075D01*
Y11481D01*
X482946D01*
Y11514D01*
X482784D01*
Y11546D01*
X482623D01*
Y11578D01*
X482462D01*
Y11610D01*
X482268D01*
Y11643D01*
X482075D01*
Y11675D01*
X481816D01*
Y11707D01*
X481558D01*
Y11739D01*
X481268D01*
Y11772D01*
X480784D01*
Y11804D01*
D02*
G37*
G36*
X476267Y-1004D02*
X476203D01*
Y-1036D01*
X476171D01*
Y-1004D01*
X472299D01*
Y-1036D01*
X472202D01*
Y-1068D01*
X472106D01*
Y-1101D01*
X472041D01*
Y-1133D01*
X472009D01*
Y-1165D01*
X471977D01*
Y-1198D01*
X471944D01*
Y-1230D01*
X471912D01*
Y-1262D01*
X471880D01*
Y-1294D01*
X471848D01*
Y-1327D01*
X471815D01*
Y-1359D01*
X471783D01*
Y-1391D01*
X471751D01*
Y-1423D01*
X471719D01*
Y-1456D01*
X471686D01*
Y-1488D01*
X471654D01*
Y-1520D01*
X471622D01*
Y-1552D01*
X471590D01*
Y-1585D01*
X471557D01*
Y-1617D01*
X471525D01*
Y-1649D01*
X471493D01*
Y-1681D01*
X471460D01*
Y-1714D01*
X471428D01*
Y-1746D01*
X471396D01*
Y-1778D01*
X471364D01*
Y-1811D01*
X471332D01*
Y-1843D01*
X471299D01*
Y-1875D01*
X471267D01*
Y-1907D01*
X471235D01*
Y-1940D01*
X471202D01*
Y-1972D01*
X471170D01*
Y-2004D01*
X471138D01*
Y-2036D01*
Y-2069D01*
X471106D01*
Y-2101D01*
Y-2133D01*
Y-2165D01*
Y-2198D01*
X471073D01*
Y-2230D01*
Y-2262D01*
Y-2294D01*
Y-2327D01*
Y-2359D01*
Y-2391D01*
Y-2424D01*
Y-2456D01*
Y-2488D01*
Y-2520D01*
Y-2553D01*
Y-2585D01*
Y-2617D01*
Y-2649D01*
Y-2682D01*
Y-2714D01*
Y-2746D01*
Y-2778D01*
Y-2811D01*
Y-2843D01*
Y-2875D01*
Y-2907D01*
Y-2940D01*
Y-2972D01*
Y-3004D01*
Y-3036D01*
Y-3069D01*
Y-3101D01*
Y-3133D01*
Y-3165D01*
Y-3198D01*
Y-3230D01*
Y-3262D01*
Y-3295D01*
Y-3327D01*
Y-3359D01*
Y-3391D01*
Y-3424D01*
Y-3456D01*
Y-3488D01*
Y-3520D01*
Y-3553D01*
Y-3585D01*
Y-3617D01*
Y-3650D01*
Y-3682D01*
Y-3714D01*
Y-3746D01*
Y-3779D01*
Y-3811D01*
Y-3843D01*
Y-3875D01*
Y-3907D01*
Y-3940D01*
Y-3972D01*
Y-4004D01*
Y-4037D01*
Y-4069D01*
Y-4101D01*
Y-4133D01*
Y-4166D01*
Y-4198D01*
Y-4230D01*
Y-4262D01*
Y-4295D01*
Y-4327D01*
Y-4359D01*
Y-4391D01*
Y-4424D01*
Y-4456D01*
Y-4488D01*
Y-4521D01*
Y-4553D01*
Y-4585D01*
Y-4617D01*
Y-4650D01*
Y-4682D01*
Y-4714D01*
Y-4746D01*
Y-4779D01*
Y-4811D01*
Y-4843D01*
Y-4875D01*
Y-4908D01*
Y-4940D01*
Y-4972D01*
Y-5004D01*
Y-5037D01*
Y-5069D01*
Y-5101D01*
Y-5133D01*
Y-5166D01*
Y-5198D01*
Y-5230D01*
Y-5263D01*
Y-5295D01*
Y-5327D01*
Y-5359D01*
Y-5392D01*
Y-5424D01*
Y-5456D01*
Y-5488D01*
Y-5521D01*
Y-5553D01*
Y-5585D01*
Y-5617D01*
Y-5650D01*
Y-5682D01*
Y-5714D01*
Y-5746D01*
Y-5779D01*
Y-5811D01*
Y-5843D01*
Y-5875D01*
Y-5908D01*
Y-5940D01*
Y-5972D01*
Y-6005D01*
Y-6037D01*
Y-6069D01*
Y-6101D01*
Y-6134D01*
Y-6166D01*
Y-6198D01*
Y-6230D01*
Y-6263D01*
Y-6295D01*
Y-6327D01*
Y-6359D01*
Y-6392D01*
Y-6424D01*
Y-6456D01*
Y-6488D01*
Y-6521D01*
Y-6553D01*
Y-6585D01*
Y-6617D01*
Y-6650D01*
Y-6682D01*
Y-6714D01*
Y-6747D01*
Y-6779D01*
Y-6811D01*
Y-6843D01*
Y-6876D01*
X471106D01*
Y-6908D01*
Y-6940D01*
Y-6972D01*
X471138D01*
Y-7005D01*
Y-7037D01*
X471170D01*
Y-7069D01*
X471202D01*
Y-7102D01*
X471235D01*
Y-7134D01*
X471267D01*
Y-7166D01*
X471299D01*
Y-7198D01*
X471332D01*
Y-7231D01*
X471364D01*
Y-7263D01*
X471396D01*
Y-7295D01*
X471428D01*
Y-7327D01*
X471460D01*
Y-7360D01*
X471493D01*
Y-7392D01*
X471525D01*
Y-7424D01*
X471557D01*
Y-7456D01*
X471590D01*
Y-7489D01*
X471622D01*
Y-7521D01*
X471654D01*
Y-7553D01*
X471686D01*
Y-7585D01*
X471719D01*
Y-7618D01*
X471751D01*
Y-7650D01*
X471783D01*
Y-7682D01*
X471815D01*
Y-7714D01*
X471848D01*
Y-7747D01*
X471880D01*
Y-7779D01*
X471912D01*
Y-7811D01*
X471944D01*
Y-7843D01*
X471977D01*
Y-7876D01*
X472009D01*
Y-7908D01*
X472041D01*
Y-7940D01*
X472074D01*
Y-7972D01*
X472138D01*
Y-8005D01*
X472235D01*
Y-8037D01*
X476332D01*
Y-8005D01*
X476364D01*
Y-7972D01*
X476397D01*
Y-7940D01*
X476429D01*
Y-7908D01*
Y-7876D01*
Y-7843D01*
Y-7811D01*
Y-7779D01*
Y-7747D01*
Y-7714D01*
Y-7682D01*
Y-7650D01*
Y-7618D01*
Y-7585D01*
Y-7553D01*
Y-7521D01*
Y-7489D01*
Y-7456D01*
Y-7424D01*
Y-7392D01*
Y-7360D01*
Y-7327D01*
Y-7295D01*
Y-7263D01*
Y-7231D01*
Y-7198D01*
Y-7166D01*
Y-7134D01*
Y-7102D01*
Y-7069D01*
Y-7037D01*
Y-7005D01*
Y-6972D01*
Y-6940D01*
Y-6908D01*
Y-6876D01*
Y-6843D01*
Y-6811D01*
Y-6779D01*
Y-6747D01*
Y-6714D01*
Y-6682D01*
Y-6650D01*
Y-6617D01*
Y-6585D01*
Y-6553D01*
Y-6521D01*
Y-6488D01*
Y-6456D01*
Y-6424D01*
X476397D01*
Y-6392D01*
X476364D01*
Y-6359D01*
X476300D01*
Y-6327D01*
X472944D01*
Y-6295D01*
X472880D01*
Y-6263D01*
Y-6230D01*
X472848D01*
Y-6198D01*
Y-6166D01*
Y-6134D01*
Y-6101D01*
Y-6069D01*
Y-6037D01*
Y-6005D01*
Y-5972D01*
Y-5940D01*
Y-5908D01*
Y-5875D01*
Y-5843D01*
Y-5811D01*
Y-5779D01*
Y-5746D01*
Y-5714D01*
Y-5682D01*
Y-5650D01*
Y-5617D01*
Y-5585D01*
Y-5553D01*
Y-5521D01*
Y-5488D01*
Y-5456D01*
Y-5424D01*
Y-5392D01*
Y-5359D01*
Y-5327D01*
Y-5295D01*
Y-5263D01*
Y-5230D01*
Y-5198D01*
Y-5166D01*
Y-5133D01*
Y-5101D01*
Y-5069D01*
Y-5037D01*
Y-5004D01*
Y-4972D01*
Y-4940D01*
Y-4908D01*
Y-4875D01*
Y-4843D01*
Y-4811D01*
Y-4779D01*
Y-4746D01*
Y-4714D01*
Y-4682D01*
Y-4650D01*
Y-4617D01*
Y-4585D01*
Y-4553D01*
Y-4521D01*
Y-4488D01*
Y-4456D01*
Y-4424D01*
Y-4391D01*
Y-4359D01*
Y-4327D01*
Y-4295D01*
Y-4262D01*
Y-4230D01*
Y-4198D01*
Y-4166D01*
Y-4133D01*
Y-4101D01*
Y-4069D01*
Y-4037D01*
Y-4004D01*
Y-3972D01*
Y-3940D01*
Y-3907D01*
Y-3875D01*
Y-3843D01*
Y-3811D01*
Y-3779D01*
Y-3746D01*
Y-3714D01*
Y-3682D01*
Y-3650D01*
Y-3617D01*
Y-3585D01*
Y-3553D01*
Y-3520D01*
Y-3488D01*
Y-3456D01*
Y-3424D01*
Y-3391D01*
Y-3359D01*
Y-3327D01*
Y-3295D01*
Y-3262D01*
Y-3230D01*
Y-3198D01*
Y-3165D01*
Y-3133D01*
Y-3101D01*
Y-3069D01*
Y-3036D01*
Y-3004D01*
Y-2972D01*
Y-2940D01*
Y-2907D01*
Y-2875D01*
Y-2843D01*
Y-2811D01*
X472880D01*
Y-2778D01*
X472912D01*
Y-2746D01*
X476106D01*
Y-2714D01*
X476138D01*
Y-2746D01*
X476267D01*
Y-2714D01*
X476364D01*
Y-2682D01*
X476397D01*
Y-2649D01*
X476429D01*
Y-2617D01*
Y-2585D01*
Y-2553D01*
Y-2520D01*
Y-2488D01*
Y-2456D01*
Y-2424D01*
Y-2391D01*
Y-2359D01*
Y-2327D01*
Y-2294D01*
Y-2262D01*
Y-2230D01*
Y-2198D01*
Y-2165D01*
Y-2133D01*
Y-2101D01*
Y-2069D01*
Y-2036D01*
Y-2004D01*
Y-1972D01*
Y-1940D01*
Y-1907D01*
Y-1875D01*
Y-1843D01*
Y-1811D01*
Y-1778D01*
Y-1746D01*
Y-1714D01*
Y-1681D01*
Y-1649D01*
Y-1617D01*
Y-1585D01*
Y-1552D01*
Y-1520D01*
Y-1488D01*
Y-1456D01*
Y-1423D01*
Y-1391D01*
Y-1359D01*
Y-1327D01*
Y-1294D01*
Y-1262D01*
Y-1230D01*
Y-1198D01*
Y-1165D01*
Y-1133D01*
Y-1101D01*
X476397D01*
Y-1068D01*
X476364D01*
Y-1036D01*
X476267D01*
Y-1004D01*
D02*
G37*
G36*
X481913D02*
X481462D01*
Y-1036D01*
X481429D01*
Y-1068D01*
X481397D01*
Y-1101D01*
X481365D01*
Y-1133D01*
X481333D01*
Y-1165D01*
X481300D01*
Y-1198D01*
X481268D01*
Y-1230D01*
X481236D01*
Y-1262D01*
X481204D01*
Y-1294D01*
X481171D01*
Y-1327D01*
X481139D01*
Y-1359D01*
X481107D01*
Y-1391D01*
X481074D01*
Y-1423D01*
X481042D01*
Y-1456D01*
X481010D01*
Y-1488D01*
X480978D01*
Y-1520D01*
X480945D01*
Y-1552D01*
X480913D01*
Y-1585D01*
X480881D01*
Y-1617D01*
X480849D01*
Y-1649D01*
X480816D01*
Y-1681D01*
X480784D01*
Y-1714D01*
X480752D01*
Y-1746D01*
X480720D01*
Y-1778D01*
X480687D01*
Y-1811D01*
X480655D01*
Y-1843D01*
X480623D01*
Y-1875D01*
X480591D01*
Y-1907D01*
X480558D01*
Y-1940D01*
X480526D01*
Y-1972D01*
X480494D01*
Y-2004D01*
X480462D01*
Y-2036D01*
X480429D01*
Y-2069D01*
X480397D01*
Y-2101D01*
X480365D01*
Y-2133D01*
X480333D01*
Y-2165D01*
X480300D01*
Y-2198D01*
X480268D01*
Y-2230D01*
X480236D01*
Y-2262D01*
X480203D01*
Y-2294D01*
X480171D01*
Y-2327D01*
X480139D01*
Y-2359D01*
X480107D01*
Y-2391D01*
X480074D01*
Y-2424D01*
X480042D01*
Y-2456D01*
X480010D01*
Y-2488D01*
X479978D01*
Y-2520D01*
X479945D01*
Y-2553D01*
X479913D01*
Y-2585D01*
X481365D01*
Y-2617D01*
Y-2649D01*
Y-2682D01*
Y-2714D01*
Y-2746D01*
Y-2778D01*
Y-2811D01*
Y-2843D01*
Y-2875D01*
Y-2907D01*
Y-2940D01*
Y-2972D01*
Y-3004D01*
Y-3036D01*
Y-3069D01*
Y-3101D01*
Y-3133D01*
Y-3165D01*
Y-3198D01*
Y-3230D01*
Y-3262D01*
Y-3295D01*
Y-3327D01*
Y-3359D01*
Y-3391D01*
Y-3424D01*
Y-3456D01*
Y-3488D01*
Y-3520D01*
Y-3553D01*
Y-3585D01*
Y-3617D01*
Y-3650D01*
Y-3682D01*
Y-3714D01*
Y-3746D01*
Y-3779D01*
Y-3811D01*
Y-3843D01*
Y-3875D01*
Y-3907D01*
Y-3940D01*
Y-3972D01*
Y-4004D01*
Y-4037D01*
Y-4069D01*
Y-4101D01*
Y-4133D01*
Y-4166D01*
Y-4198D01*
Y-4230D01*
Y-4262D01*
Y-4295D01*
Y-4327D01*
Y-4359D01*
X479010D01*
Y-4327D01*
Y-4295D01*
Y-4262D01*
Y-4230D01*
Y-4198D01*
Y-4166D01*
Y-4133D01*
Y-4101D01*
Y-4069D01*
Y-4037D01*
Y-4004D01*
Y-3972D01*
Y-3940D01*
Y-3907D01*
Y-3875D01*
Y-3843D01*
Y-3811D01*
Y-3779D01*
Y-3746D01*
Y-3714D01*
Y-3682D01*
Y-3650D01*
X478977D01*
Y-3682D01*
X478945D01*
Y-3714D01*
X478913D01*
Y-3746D01*
X478881D01*
Y-3779D01*
X478849D01*
Y-3811D01*
X478816D01*
Y-3843D01*
X478784D01*
Y-3875D01*
X478752D01*
Y-3907D01*
X478719D01*
Y-3940D01*
X478687D01*
Y-3972D01*
X478655D01*
Y-4004D01*
X478623D01*
Y-4037D01*
X478590D01*
Y-4069D01*
X478558D01*
Y-4101D01*
X478526D01*
Y-4133D01*
X478494D01*
Y-4166D01*
X478461D01*
Y-4198D01*
X478429D01*
Y-4230D01*
X478397D01*
Y-4262D01*
X478365D01*
Y-4295D01*
X478332D01*
Y-4327D01*
X478300D01*
Y-4359D01*
X478268D01*
Y-4391D01*
X478235D01*
Y-4424D01*
X478203D01*
Y-4456D01*
X478171D01*
Y-4488D01*
X478139D01*
Y-4521D01*
X478106D01*
Y-4553D01*
X478074D01*
Y-4585D01*
X478042D01*
Y-4617D01*
X478010D01*
Y-4650D01*
X477977D01*
Y-4682D01*
X477945D01*
Y-4714D01*
X477913D01*
Y-4746D01*
X477881D01*
Y-4779D01*
X477848D01*
Y-4811D01*
X477816D01*
Y-4843D01*
X477784D01*
Y-4875D01*
X477752D01*
Y-4908D01*
X477719D01*
Y-4940D01*
X477687D01*
Y-4972D01*
X477655D01*
Y-5004D01*
X477623D01*
Y-5037D01*
X477590D01*
Y-5069D01*
X477558D01*
Y-5101D01*
X477526D01*
Y-5133D01*
X477493D01*
Y-5166D01*
X477429D01*
Y-5198D01*
X477397D01*
Y-5230D01*
X477364D01*
Y-5263D01*
X477332D01*
Y-5295D01*
X477300D01*
Y-5327D01*
X477268D01*
Y-5359D01*
X477235D01*
Y-5392D01*
Y-5424D01*
Y-5456D01*
Y-5488D01*
Y-5521D01*
Y-5553D01*
Y-5585D01*
Y-5617D01*
Y-5650D01*
Y-5682D01*
Y-5714D01*
Y-5746D01*
Y-5779D01*
Y-5811D01*
Y-5843D01*
Y-5875D01*
Y-5908D01*
Y-5940D01*
Y-5972D01*
Y-6005D01*
Y-6037D01*
Y-6069D01*
Y-6101D01*
Y-6134D01*
Y-6166D01*
Y-6198D01*
Y-6230D01*
Y-6263D01*
Y-6295D01*
Y-6327D01*
Y-6359D01*
Y-6392D01*
Y-6424D01*
Y-6456D01*
Y-6488D01*
Y-6521D01*
Y-6553D01*
Y-6585D01*
Y-6617D01*
Y-6650D01*
Y-6682D01*
Y-6714D01*
Y-6747D01*
Y-6779D01*
Y-6811D01*
Y-6843D01*
Y-6876D01*
Y-6908D01*
Y-6940D01*
Y-6972D01*
Y-7005D01*
Y-7037D01*
Y-7069D01*
Y-7102D01*
Y-7134D01*
Y-7166D01*
Y-7198D01*
Y-7231D01*
Y-7263D01*
Y-7295D01*
Y-7327D01*
Y-7360D01*
Y-7392D01*
Y-7424D01*
Y-7456D01*
Y-7489D01*
Y-7521D01*
Y-7553D01*
Y-7585D01*
Y-7618D01*
Y-7650D01*
Y-7682D01*
Y-7714D01*
Y-7747D01*
Y-7779D01*
Y-7811D01*
Y-7843D01*
Y-7876D01*
Y-7908D01*
Y-7940D01*
X477268D01*
Y-7972D01*
X477300D01*
Y-8005D01*
X477364D01*
Y-8037D01*
X478881D01*
Y-8005D01*
X478945D01*
Y-7972D01*
X478977D01*
Y-7940D01*
Y-7908D01*
X479010D01*
Y-7876D01*
Y-7843D01*
Y-7811D01*
Y-7779D01*
Y-7747D01*
Y-7714D01*
Y-7682D01*
Y-7650D01*
Y-7618D01*
Y-7585D01*
Y-7553D01*
Y-7521D01*
Y-7489D01*
Y-7456D01*
Y-7424D01*
Y-7392D01*
Y-7360D01*
Y-7327D01*
Y-7295D01*
Y-7263D01*
Y-7231D01*
Y-7198D01*
Y-7166D01*
Y-7134D01*
Y-7102D01*
Y-7069D01*
Y-7037D01*
Y-7005D01*
Y-6972D01*
Y-6940D01*
Y-6908D01*
Y-6876D01*
Y-6843D01*
Y-6811D01*
Y-6779D01*
Y-6747D01*
Y-6714D01*
Y-6682D01*
Y-6650D01*
Y-6617D01*
Y-6585D01*
Y-6553D01*
Y-6521D01*
Y-6488D01*
Y-6456D01*
Y-6424D01*
Y-6392D01*
Y-6359D01*
Y-6327D01*
Y-6295D01*
Y-6263D01*
Y-6230D01*
Y-6198D01*
Y-6166D01*
Y-6134D01*
Y-6101D01*
Y-6069D01*
Y-6037D01*
Y-6005D01*
Y-5972D01*
X479042D01*
Y-5940D01*
Y-5908D01*
X479107D01*
Y-5875D01*
X481268D01*
Y-5908D01*
X481333D01*
Y-5940D01*
Y-5972D01*
X481365D01*
Y-6005D01*
Y-6037D01*
Y-6069D01*
Y-6101D01*
Y-6134D01*
Y-6166D01*
Y-6198D01*
Y-6230D01*
Y-6263D01*
Y-6295D01*
Y-6327D01*
Y-6359D01*
Y-6392D01*
Y-6424D01*
Y-6456D01*
Y-6488D01*
Y-6521D01*
Y-6553D01*
Y-6585D01*
Y-6617D01*
Y-6650D01*
Y-6682D01*
Y-6714D01*
Y-6747D01*
Y-6779D01*
Y-6811D01*
Y-6843D01*
Y-6876D01*
Y-6908D01*
Y-6940D01*
Y-6972D01*
Y-7005D01*
Y-7037D01*
Y-7069D01*
Y-7102D01*
Y-7134D01*
Y-7166D01*
Y-7198D01*
Y-7231D01*
Y-7263D01*
Y-7295D01*
Y-7327D01*
Y-7360D01*
Y-7392D01*
Y-7424D01*
Y-7456D01*
Y-7489D01*
Y-7521D01*
Y-7553D01*
Y-7585D01*
Y-7618D01*
Y-7650D01*
Y-7682D01*
Y-7714D01*
Y-7747D01*
Y-7779D01*
Y-7811D01*
Y-7843D01*
Y-7876D01*
Y-7908D01*
Y-7940D01*
X481397D01*
Y-7972D01*
X481429D01*
Y-8005D01*
X481494D01*
Y-8037D01*
X483010D01*
Y-8005D01*
X483075D01*
Y-7972D01*
X483107D01*
Y-7940D01*
Y-7908D01*
X483139D01*
Y-7876D01*
Y-7843D01*
Y-7811D01*
Y-7779D01*
Y-7747D01*
Y-7714D01*
Y-7682D01*
Y-7650D01*
Y-7618D01*
Y-7585D01*
Y-7553D01*
Y-7521D01*
Y-7489D01*
Y-7456D01*
Y-7424D01*
Y-7392D01*
Y-7360D01*
Y-7327D01*
Y-7295D01*
Y-7263D01*
Y-7231D01*
Y-7198D01*
Y-7166D01*
Y-7134D01*
Y-7102D01*
Y-7069D01*
Y-7037D01*
Y-7005D01*
Y-6972D01*
Y-6940D01*
Y-6908D01*
Y-6876D01*
Y-6843D01*
Y-6811D01*
Y-6779D01*
Y-6747D01*
Y-6714D01*
Y-6682D01*
Y-6650D01*
Y-6617D01*
Y-6585D01*
Y-6553D01*
Y-6521D01*
Y-6488D01*
Y-6456D01*
Y-6424D01*
Y-6392D01*
Y-6359D01*
Y-6327D01*
Y-6295D01*
Y-6263D01*
Y-6230D01*
Y-6198D01*
Y-6166D01*
Y-6134D01*
Y-6101D01*
Y-6069D01*
Y-6037D01*
Y-6005D01*
Y-5972D01*
Y-5940D01*
Y-5908D01*
Y-5875D01*
Y-5843D01*
Y-5811D01*
Y-5779D01*
Y-5746D01*
Y-5714D01*
Y-5682D01*
Y-5650D01*
Y-5617D01*
Y-5585D01*
Y-5553D01*
Y-5521D01*
Y-5488D01*
Y-5456D01*
Y-5424D01*
Y-5392D01*
Y-5359D01*
Y-5327D01*
Y-5295D01*
Y-5263D01*
Y-5230D01*
Y-5198D01*
Y-5166D01*
Y-5133D01*
Y-5101D01*
Y-5069D01*
Y-5037D01*
Y-5004D01*
Y-4972D01*
Y-4940D01*
Y-4908D01*
Y-4875D01*
Y-4843D01*
Y-4811D01*
Y-4779D01*
Y-4746D01*
Y-4714D01*
Y-4682D01*
Y-4650D01*
Y-4617D01*
Y-4585D01*
Y-4553D01*
Y-4521D01*
Y-4488D01*
Y-4456D01*
Y-4424D01*
Y-4391D01*
Y-4359D01*
Y-4327D01*
Y-4295D01*
Y-4262D01*
Y-4230D01*
Y-4198D01*
Y-4166D01*
Y-4133D01*
Y-4101D01*
Y-4069D01*
Y-4037D01*
Y-4004D01*
Y-3972D01*
Y-3940D01*
Y-3907D01*
Y-3875D01*
Y-3843D01*
Y-3811D01*
Y-3779D01*
Y-3746D01*
Y-3714D01*
Y-3682D01*
Y-3650D01*
Y-3617D01*
Y-3585D01*
Y-3553D01*
Y-3520D01*
Y-3488D01*
Y-3456D01*
Y-3424D01*
Y-3391D01*
Y-3359D01*
Y-3327D01*
Y-3295D01*
Y-3262D01*
Y-3230D01*
Y-3198D01*
Y-3165D01*
Y-3133D01*
Y-3101D01*
Y-3069D01*
Y-3036D01*
Y-3004D01*
Y-2972D01*
Y-2940D01*
Y-2907D01*
Y-2875D01*
Y-2843D01*
Y-2811D01*
Y-2778D01*
Y-2746D01*
Y-2714D01*
Y-2682D01*
Y-2649D01*
Y-2617D01*
Y-2585D01*
Y-2553D01*
Y-2520D01*
Y-2488D01*
Y-2456D01*
Y-2424D01*
Y-2391D01*
Y-2359D01*
Y-2327D01*
Y-2294D01*
Y-2262D01*
Y-2230D01*
X483107D01*
Y-2198D01*
Y-2165D01*
Y-2133D01*
Y-2101D01*
X483075D01*
Y-2069D01*
Y-2036D01*
Y-2004D01*
X483042D01*
Y-1972D01*
X483010D01*
Y-1940D01*
X482978D01*
Y-1907D01*
X482946D01*
Y-1875D01*
X482913D01*
Y-1843D01*
X482881D01*
Y-1811D01*
X482849D01*
Y-1778D01*
X482817D01*
Y-1746D01*
X482784D01*
Y-1714D01*
X482752D01*
Y-1681D01*
X482720D01*
Y-1649D01*
X482688D01*
Y-1617D01*
X482655D01*
Y-1585D01*
X482623D01*
Y-1552D01*
X482591D01*
Y-1520D01*
X482559D01*
Y-1488D01*
X482526D01*
Y-1456D01*
X482494D01*
Y-1423D01*
X482462D01*
Y-1391D01*
X482430D01*
Y-1359D01*
X482397D01*
Y-1327D01*
X482365D01*
Y-1294D01*
X482333D01*
Y-1262D01*
X482301D01*
Y-1230D01*
X482268D01*
Y-1198D01*
X482236D01*
Y-1165D01*
X482204D01*
Y-1133D01*
X482171D01*
Y-1101D01*
X482107D01*
Y-1068D01*
X482042D01*
Y-1036D01*
X481913D01*
Y-1004D01*
D02*
G37*
G36*
X479687Y10449D02*
X479107D01*
Y10417D01*
Y10384D01*
Y10352D01*
Y10320D01*
Y10288D01*
Y10255D01*
Y10223D01*
Y10191D01*
Y10159D01*
Y10126D01*
Y10094D01*
Y10062D01*
Y10029D01*
Y9997D01*
Y9965D01*
Y9933D01*
Y9900D01*
Y9868D01*
Y9836D01*
Y9804D01*
Y9771D01*
Y9739D01*
Y9707D01*
Y9675D01*
Y9642D01*
Y9610D01*
Y9578D01*
Y9546D01*
Y9513D01*
Y9481D01*
Y9449D01*
Y9417D01*
Y9384D01*
Y9352D01*
Y9320D01*
Y9287D01*
Y9255D01*
Y9223D01*
Y9191D01*
Y9159D01*
Y9126D01*
Y9094D01*
Y9062D01*
Y9029D01*
Y8997D01*
Y8965D01*
Y8933D01*
Y8900D01*
Y8868D01*
Y8836D01*
Y8804D01*
Y8771D01*
Y8739D01*
Y8707D01*
Y8675D01*
Y8642D01*
Y8610D01*
Y8578D01*
Y8546D01*
Y8513D01*
Y8481D01*
Y8449D01*
Y8416D01*
Y8384D01*
Y8352D01*
Y8320D01*
Y8287D01*
Y8255D01*
Y8223D01*
Y8191D01*
Y8158D01*
Y8126D01*
Y8094D01*
Y8062D01*
Y8029D01*
Y7997D01*
Y7965D01*
Y7932D01*
Y7900D01*
Y7868D01*
Y7836D01*
Y7803D01*
Y7771D01*
Y7739D01*
Y7707D01*
Y7674D01*
Y7642D01*
Y7610D01*
Y7578D01*
Y7545D01*
Y7513D01*
Y7481D01*
Y7449D01*
Y7416D01*
Y7384D01*
Y7352D01*
Y7320D01*
Y7287D01*
Y7255D01*
Y7223D01*
Y7191D01*
Y7158D01*
Y7126D01*
Y7094D01*
Y7062D01*
Y7029D01*
Y6997D01*
Y6965D01*
Y6932D01*
Y6900D01*
Y6868D01*
Y6836D01*
Y6803D01*
Y6771D01*
Y6739D01*
Y6707D01*
Y6674D01*
Y6642D01*
Y6610D01*
Y6577D01*
Y6545D01*
Y6513D01*
Y6481D01*
Y6448D01*
Y6416D01*
Y6384D01*
Y6352D01*
Y6319D01*
Y6287D01*
Y6255D01*
Y6223D01*
Y6190D01*
Y6158D01*
Y6126D01*
Y6094D01*
Y6061D01*
Y6029D01*
Y5997D01*
Y5965D01*
Y5932D01*
Y5900D01*
Y5868D01*
Y5835D01*
Y5803D01*
Y5771D01*
Y5739D01*
Y5706D01*
Y5674D01*
Y5642D01*
Y5610D01*
Y5577D01*
Y5545D01*
Y5513D01*
Y5481D01*
Y5448D01*
Y5416D01*
Y5384D01*
Y5352D01*
Y5319D01*
Y5287D01*
Y5255D01*
Y5223D01*
Y5190D01*
Y5158D01*
Y5126D01*
Y5094D01*
Y5061D01*
Y5029D01*
Y4997D01*
Y4964D01*
Y4932D01*
Y4900D01*
Y4868D01*
Y4835D01*
Y4803D01*
Y4771D01*
Y4739D01*
Y4706D01*
Y4674D01*
Y4642D01*
Y4610D01*
Y4577D01*
Y4545D01*
Y4513D01*
Y4481D01*
Y4448D01*
Y4416D01*
Y4384D01*
Y4352D01*
Y4319D01*
Y4287D01*
Y4255D01*
Y4222D01*
Y4190D01*
Y4158D01*
Y4126D01*
Y4093D01*
Y4061D01*
Y4029D01*
Y3997D01*
Y3964D01*
Y3932D01*
Y3900D01*
Y3867D01*
Y3835D01*
Y3803D01*
Y3771D01*
Y3739D01*
Y3706D01*
Y3674D01*
Y3642D01*
Y3609D01*
Y3577D01*
Y3545D01*
Y3513D01*
Y3480D01*
Y3448D01*
Y3416D01*
Y3384D01*
Y3351D01*
Y3319D01*
Y3287D01*
Y3255D01*
Y3222D01*
Y3190D01*
Y3158D01*
Y3125D01*
Y3093D01*
Y3061D01*
Y3029D01*
Y2997D01*
Y2964D01*
Y2932D01*
Y2900D01*
Y2867D01*
Y2835D01*
Y2803D01*
Y2771D01*
Y2738D01*
Y2706D01*
Y2674D01*
Y2642D01*
Y2609D01*
Y2577D01*
Y2545D01*
Y2513D01*
Y2480D01*
Y2448D01*
Y2416D01*
Y2383D01*
Y2351D01*
Y2319D01*
Y2287D01*
Y2254D01*
Y2222D01*
Y2190D01*
Y2158D01*
Y2125D01*
Y2093D01*
Y2061D01*
Y2029D01*
Y1996D01*
Y1964D01*
Y1932D01*
Y1900D01*
Y1867D01*
Y1835D01*
Y1803D01*
Y1770D01*
Y1738D01*
Y1706D01*
Y1674D01*
Y1641D01*
Y1609D01*
Y1577D01*
Y1545D01*
Y1512D01*
Y1480D01*
Y1448D01*
Y1416D01*
Y1383D01*
Y1351D01*
Y1319D01*
Y1287D01*
Y1254D01*
Y1222D01*
Y1190D01*
Y1158D01*
Y1125D01*
Y1093D01*
Y1061D01*
Y1029D01*
Y996D01*
Y964D01*
Y932D01*
Y900D01*
Y867D01*
Y835D01*
Y803D01*
Y770D01*
Y738D01*
Y706D01*
Y674D01*
Y641D01*
Y609D01*
Y577D01*
Y545D01*
Y512D01*
Y480D01*
Y448D01*
Y416D01*
Y383D01*
Y351D01*
Y319D01*
Y286D01*
Y254D01*
Y222D01*
Y190D01*
Y157D01*
Y125D01*
Y93D01*
Y61D01*
Y28D01*
Y-4D01*
Y-36D01*
Y-68D01*
Y-101D01*
Y-133D01*
Y-165D01*
Y-197D01*
Y-230D01*
X479074D01*
Y-262D01*
X479042D01*
Y-294D01*
X479010D01*
Y-326D01*
X478977D01*
Y-359D01*
X478945D01*
Y-391D01*
X478913D01*
Y-423D01*
X478881D01*
Y-455D01*
X478849D01*
Y-488D01*
X478816D01*
Y-520D01*
X478784D01*
Y-552D01*
X478752D01*
Y-585D01*
X478719D01*
Y-617D01*
X478687D01*
Y-649D01*
X478655D01*
Y-681D01*
X478623D01*
Y-714D01*
X478590D01*
Y-746D01*
X478558D01*
Y-778D01*
X478494D01*
Y-810D01*
X478461D01*
Y-843D01*
X478429D01*
Y-875D01*
X478397D01*
Y-907D01*
X478365D01*
Y-939D01*
X478332D01*
Y-972D01*
X478300D01*
Y-1004D01*
X478268D01*
Y-1036D01*
X478235D01*
Y-1068D01*
X478203D01*
Y-1101D01*
X478171D01*
Y-1133D01*
X478139D01*
Y-1165D01*
X478106D01*
Y-1198D01*
X478074D01*
Y-1230D01*
X478042D01*
Y-1262D01*
X478010D01*
Y-1294D01*
X477977D01*
Y-1327D01*
X477945D01*
Y-1359D01*
X477913D01*
Y-1391D01*
X477881D01*
Y-1423D01*
X477848D01*
Y-1456D01*
X477816D01*
Y-1488D01*
X477784D01*
Y-1520D01*
X477752D01*
Y-1552D01*
X477719D01*
Y-1585D01*
X477687D01*
Y-1617D01*
X477655D01*
Y-1649D01*
X477623D01*
Y-1681D01*
X477590D01*
Y-1714D01*
X477558D01*
Y-1746D01*
X477526D01*
Y-1778D01*
X477493D01*
Y-1811D01*
X477461D01*
Y-1843D01*
X477429D01*
Y-1875D01*
X477397D01*
Y-1907D01*
X477364D01*
Y-1940D01*
X477332D01*
Y-1972D01*
X477300D01*
Y-2004D01*
X477268D01*
Y-2036D01*
X477235D01*
Y-2069D01*
X477203D01*
Y-2101D01*
X477171D01*
Y-2133D01*
X477139D01*
Y-2165D01*
X477106D01*
Y-2198D01*
X477074D01*
Y-2230D01*
X477042D01*
Y-2262D01*
X477009D01*
Y-2294D01*
X476977D01*
Y-2327D01*
X476945D01*
Y-2359D01*
X476913D01*
Y-2391D01*
X476881D01*
Y-2424D01*
X476848D01*
Y-2456D01*
X476816D01*
Y-2488D01*
X476784D01*
Y-2520D01*
X476751D01*
Y-2553D01*
X476719D01*
Y-2585D01*
X476687D01*
Y-2617D01*
X476655D01*
Y-2649D01*
X476622D01*
Y-2682D01*
X476590D01*
Y-2714D01*
X476558D01*
Y-2746D01*
X476526D01*
Y-2778D01*
X476493D01*
Y-2811D01*
X476461D01*
Y-2843D01*
X476429D01*
Y-2875D01*
X476397D01*
Y-2907D01*
X476364D01*
Y-2940D01*
X476300D01*
Y-2972D01*
X476267D01*
Y-3004D01*
X476235D01*
Y-3036D01*
X476203D01*
Y-3069D01*
X476171D01*
Y-3101D01*
X476138D01*
Y-3133D01*
X476106D01*
Y-3165D01*
X476074D01*
Y-3198D01*
X476042D01*
Y-3230D01*
X476009D01*
Y-3262D01*
X475977D01*
Y-3295D01*
X475945D01*
Y-3327D01*
X475913D01*
Y-3359D01*
X475880D01*
Y-3391D01*
X475848D01*
Y-3424D01*
X475816D01*
Y-3456D01*
X475784D01*
Y-3488D01*
Y-3520D01*
X475751D01*
Y-3553D01*
X475719D01*
Y-3585D01*
Y-3617D01*
X475687D01*
Y-3650D01*
Y-3682D01*
X475655D01*
Y-3714D01*
Y-3746D01*
Y-3779D01*
Y-3811D01*
Y-3843D01*
Y-3875D01*
Y-3907D01*
Y-3940D01*
Y-3972D01*
Y-4004D01*
Y-4037D01*
Y-4069D01*
Y-4101D01*
Y-4133D01*
Y-4166D01*
Y-4198D01*
Y-4230D01*
Y-4262D01*
Y-4295D01*
Y-4327D01*
Y-4359D01*
Y-4391D01*
Y-4424D01*
Y-4456D01*
Y-4488D01*
Y-4521D01*
Y-4553D01*
Y-4585D01*
Y-4617D01*
Y-4650D01*
Y-4682D01*
Y-4714D01*
Y-4746D01*
Y-4779D01*
Y-4811D01*
Y-4843D01*
Y-4875D01*
Y-4908D01*
Y-4940D01*
Y-4972D01*
Y-5004D01*
Y-5037D01*
Y-5069D01*
Y-5101D01*
Y-5133D01*
X475687D01*
Y-5166D01*
X475719D01*
Y-5198D01*
Y-5230D01*
X475751D01*
Y-5263D01*
X475784D01*
Y-5295D01*
Y-5327D01*
X475816D01*
Y-5359D01*
X475848D01*
Y-5392D01*
X475880D01*
Y-5424D01*
X475913D01*
Y-5456D01*
X475945D01*
Y-5488D01*
X475977D01*
Y-5521D01*
X476009D01*
Y-5553D01*
X476042D01*
Y-5585D01*
X476074D01*
Y-5617D01*
X476138D01*
Y-5585D01*
X476171D01*
Y-5553D01*
X476203D01*
Y-5521D01*
X476235D01*
Y-5488D01*
X476267D01*
Y-5456D01*
X476300D01*
Y-5424D01*
X476332D01*
Y-5392D01*
X476364D01*
Y-5359D01*
X476397D01*
Y-5327D01*
X476429D01*
Y-5295D01*
X476461D01*
Y-5263D01*
X476493D01*
Y-5230D01*
X476526D01*
Y-5198D01*
X476558D01*
Y-5166D01*
X476590D01*
Y-5133D01*
X476622D01*
Y-5101D01*
X476655D01*
Y-5069D01*
X476687D01*
Y-5037D01*
X476719D01*
Y-5004D01*
X476751D01*
Y-4972D01*
X476784D01*
Y-4940D01*
X476816D01*
Y-4908D01*
X476848D01*
Y-4875D01*
X476881D01*
Y-4843D01*
X476945D01*
Y-4811D01*
X476977D01*
Y-4779D01*
X477009D01*
Y-4746D01*
X477042D01*
Y-4714D01*
X477074D01*
Y-4682D01*
X477106D01*
Y-4650D01*
X477139D01*
Y-4617D01*
X477171D01*
Y-4585D01*
X477203D01*
Y-4553D01*
X477235D01*
Y-4521D01*
X477268D01*
Y-4488D01*
X477300D01*
Y-4456D01*
X477332D01*
Y-4424D01*
X477364D01*
Y-4391D01*
X477397D01*
Y-4359D01*
X477429D01*
Y-4327D01*
X477461D01*
Y-4295D01*
X477493D01*
Y-4262D01*
X477526D01*
Y-4230D01*
X477558D01*
Y-4198D01*
X477590D01*
Y-4166D01*
X477623D01*
Y-4133D01*
X477655D01*
Y-4101D01*
X477687D01*
Y-4069D01*
X477719D01*
Y-4037D01*
X477752D01*
Y-4004D01*
X477784D01*
Y-3972D01*
X477816D01*
Y-3940D01*
X477848D01*
Y-3907D01*
X477881D01*
Y-3875D01*
X477913D01*
Y-3843D01*
X477945D01*
Y-3811D01*
X477977D01*
Y-3779D01*
X478010D01*
Y-3746D01*
X478042D01*
Y-3714D01*
X478074D01*
Y-3682D01*
X478106D01*
Y-3650D01*
X478139D01*
Y-3617D01*
X478171D01*
Y-3585D01*
X478203D01*
Y-3553D01*
X478235D01*
Y-3520D01*
X478268D01*
Y-3488D01*
X478300D01*
Y-3456D01*
X478332D01*
Y-3424D01*
X478365D01*
Y-3391D01*
X478397D01*
Y-3359D01*
X478429D01*
Y-3327D01*
X478461D01*
Y-3295D01*
X478494D01*
Y-3262D01*
X478526D01*
Y-3230D01*
X478558D01*
Y-3198D01*
X478590D01*
Y-3165D01*
X478623D01*
Y-3133D01*
X478655D01*
Y-3101D01*
X478687D01*
Y-3069D01*
X478719D01*
Y-3036D01*
X478752D01*
Y-3004D01*
X478784D01*
Y-2972D01*
X478816D01*
Y-2940D01*
X478849D01*
Y-2907D01*
X478881D01*
Y-2875D01*
X478913D01*
Y-2843D01*
X478945D01*
Y-2811D01*
X478977D01*
Y-2778D01*
X479010D01*
Y-2746D01*
X479042D01*
Y-2714D01*
X479074D01*
Y-2682D01*
X479107D01*
Y-2649D01*
X479139D01*
Y-2617D01*
X479171D01*
Y-2585D01*
X479203D01*
Y-2553D01*
X479236D01*
Y-2520D01*
X479268D01*
Y-2488D01*
X479300D01*
Y-2456D01*
X479332D01*
Y-2424D01*
X479365D01*
Y-2391D01*
X479397D01*
Y-2359D01*
X479429D01*
Y-2327D01*
X479461D01*
Y-2294D01*
X479494D01*
Y-2262D01*
X479526D01*
Y-2230D01*
X479558D01*
Y-2198D01*
X479591D01*
Y-2165D01*
X479623D01*
Y-2133D01*
X479687D01*
Y-2101D01*
X479719D01*
Y-2069D01*
X479752D01*
Y-2036D01*
X479784D01*
Y-2004D01*
X479816D01*
Y-1972D01*
X479849D01*
Y-1940D01*
X479881D01*
Y-1907D01*
X479913D01*
Y-1875D01*
X479945D01*
Y-1843D01*
X479978D01*
Y-1811D01*
X480010D01*
Y-1778D01*
X480042D01*
Y-1746D01*
X480074D01*
Y-1714D01*
X480107D01*
Y-1681D01*
X480139D01*
Y-1649D01*
X480171D01*
Y-1617D01*
X480203D01*
Y-1585D01*
X480236D01*
Y-1552D01*
X480268D01*
Y-1520D01*
X480300D01*
Y-1488D01*
X480333D01*
Y-1456D01*
X480365D01*
Y-1423D01*
X480397D01*
Y-1391D01*
X480429D01*
Y-1359D01*
X480462D01*
Y-1327D01*
X480494D01*
Y-1294D01*
X480526D01*
Y-1262D01*
X480558D01*
Y-1230D01*
X480591D01*
Y-1198D01*
X480623D01*
Y-1165D01*
X480655D01*
Y-1133D01*
Y-1101D01*
X480687D01*
Y-1068D01*
X480720D01*
Y-1036D01*
Y-1004D01*
X480752D01*
Y-972D01*
Y-939D01*
X480784D01*
Y-907D01*
Y-875D01*
X480816D01*
Y-843D01*
Y-810D01*
Y-778D01*
Y-746D01*
X480849D01*
Y-714D01*
Y-681D01*
Y-649D01*
Y-617D01*
Y-585D01*
Y-552D01*
Y-520D01*
Y-488D01*
Y-455D01*
Y-423D01*
Y-391D01*
Y-359D01*
Y-326D01*
Y-294D01*
Y-262D01*
Y-230D01*
Y-197D01*
Y-165D01*
Y-133D01*
Y-101D01*
Y-68D01*
Y-36D01*
Y-4D01*
Y28D01*
Y61D01*
Y93D01*
Y125D01*
Y157D01*
Y190D01*
Y222D01*
Y254D01*
Y286D01*
Y319D01*
Y351D01*
Y383D01*
Y416D01*
Y448D01*
Y480D01*
Y512D01*
Y545D01*
Y577D01*
Y609D01*
Y641D01*
Y674D01*
Y706D01*
Y738D01*
Y770D01*
Y803D01*
Y835D01*
Y867D01*
Y900D01*
Y932D01*
Y964D01*
Y996D01*
Y1029D01*
Y1061D01*
Y1093D01*
Y1125D01*
Y1158D01*
Y1190D01*
Y1222D01*
Y1254D01*
Y1287D01*
Y1319D01*
Y1351D01*
Y1383D01*
Y1416D01*
Y1448D01*
Y1480D01*
Y1512D01*
Y1545D01*
Y1577D01*
Y1609D01*
Y1641D01*
Y1674D01*
Y1706D01*
Y1738D01*
Y1770D01*
Y1803D01*
Y1835D01*
Y1867D01*
Y1900D01*
Y1932D01*
Y1964D01*
Y1996D01*
Y2029D01*
Y2061D01*
Y2093D01*
Y2125D01*
Y2158D01*
Y2190D01*
Y2222D01*
Y2254D01*
Y2287D01*
Y2319D01*
Y2351D01*
Y2383D01*
Y2416D01*
Y2448D01*
Y2480D01*
Y2513D01*
Y2545D01*
Y2577D01*
Y2609D01*
Y2642D01*
Y2674D01*
Y2706D01*
Y2738D01*
Y2771D01*
Y2803D01*
Y2835D01*
Y2867D01*
Y2900D01*
Y2932D01*
Y2964D01*
Y2997D01*
Y3029D01*
Y3061D01*
Y3093D01*
Y3125D01*
Y3158D01*
Y3190D01*
Y3222D01*
Y3255D01*
Y3287D01*
Y3319D01*
Y3351D01*
Y3384D01*
Y3416D01*
Y3448D01*
Y3480D01*
Y3513D01*
Y3545D01*
Y3577D01*
Y3609D01*
Y3642D01*
Y3674D01*
Y3706D01*
Y3739D01*
Y3771D01*
Y3803D01*
Y3835D01*
Y3867D01*
Y3900D01*
Y3932D01*
Y3964D01*
Y3997D01*
Y4029D01*
Y4061D01*
Y4093D01*
Y4126D01*
Y4158D01*
Y4190D01*
Y4222D01*
Y4255D01*
Y4287D01*
Y4319D01*
Y4352D01*
Y4384D01*
Y4416D01*
Y4448D01*
Y4481D01*
Y4513D01*
Y4545D01*
Y4577D01*
Y4610D01*
Y4642D01*
Y4674D01*
Y4706D01*
Y4739D01*
Y4771D01*
Y4803D01*
Y4835D01*
Y4868D01*
Y4900D01*
Y4932D01*
Y4964D01*
Y4997D01*
Y5029D01*
Y5061D01*
Y5094D01*
Y5126D01*
Y5158D01*
Y5190D01*
Y5223D01*
Y5255D01*
Y5287D01*
Y5319D01*
Y5352D01*
Y5384D01*
Y5416D01*
Y5448D01*
Y5481D01*
Y5513D01*
Y5545D01*
Y5577D01*
Y5610D01*
Y5642D01*
Y5674D01*
Y5706D01*
Y5739D01*
Y5771D01*
Y5803D01*
Y5835D01*
Y5868D01*
Y5900D01*
Y5932D01*
Y5965D01*
Y5997D01*
Y6029D01*
Y6061D01*
Y6094D01*
Y6126D01*
Y6158D01*
Y6190D01*
Y6223D01*
Y6255D01*
Y6287D01*
Y6319D01*
Y6352D01*
Y6384D01*
Y6416D01*
Y6448D01*
Y6481D01*
Y6513D01*
Y6545D01*
Y6577D01*
Y6610D01*
Y6642D01*
Y6674D01*
Y6707D01*
Y6739D01*
Y6771D01*
Y6803D01*
Y6836D01*
Y6868D01*
Y6900D01*
Y6932D01*
Y6965D01*
Y6997D01*
Y7029D01*
Y7062D01*
Y7094D01*
Y7126D01*
Y7158D01*
Y7191D01*
Y7223D01*
Y7255D01*
Y7287D01*
Y7320D01*
Y7352D01*
Y7384D01*
Y7416D01*
Y7449D01*
Y7481D01*
Y7513D01*
Y7545D01*
Y7578D01*
Y7610D01*
Y7642D01*
Y7674D01*
Y7707D01*
Y7739D01*
Y7771D01*
Y7803D01*
Y7836D01*
Y7868D01*
Y7900D01*
Y7932D01*
Y7965D01*
Y7997D01*
Y8029D01*
Y8062D01*
Y8094D01*
Y8126D01*
Y8158D01*
Y8191D01*
Y8223D01*
Y8255D01*
Y8287D01*
Y8320D01*
Y8352D01*
Y8384D01*
Y8416D01*
Y8449D01*
Y8481D01*
Y8513D01*
Y8546D01*
Y8578D01*
Y8610D01*
Y8642D01*
Y8675D01*
Y8707D01*
Y8739D01*
Y8771D01*
Y8804D01*
Y8836D01*
Y8868D01*
Y8900D01*
Y8933D01*
Y8965D01*
Y8997D01*
Y9029D01*
Y9062D01*
Y9094D01*
Y9126D01*
Y9159D01*
Y9191D01*
Y9223D01*
Y9255D01*
Y9287D01*
X480816D01*
Y9320D01*
Y9352D01*
Y9384D01*
Y9417D01*
X480784D01*
Y9449D01*
Y9481D01*
X480752D01*
Y9513D01*
X480720D01*
Y9546D01*
X480687D01*
Y9578D01*
X480655D01*
Y9610D01*
X480623D01*
Y9642D01*
X480591D01*
Y9675D01*
X480558D01*
Y9707D01*
X480526D01*
Y9739D01*
X480494D01*
Y9771D01*
X480462D01*
Y9804D01*
X480429D01*
Y9836D01*
X480397D01*
Y9868D01*
X480365D01*
Y9900D01*
X480333D01*
Y9933D01*
X480300D01*
Y9965D01*
X480268D01*
Y9997D01*
X480236D01*
Y10029D01*
X480203D01*
Y10062D01*
X480171D01*
Y10094D01*
X480139D01*
Y10126D01*
X480107D01*
Y10159D01*
X480074D01*
Y10191D01*
X480042D01*
Y10223D01*
X480010D01*
Y10255D01*
X479978D01*
Y10288D01*
X479945D01*
Y10320D01*
X479913D01*
Y10352D01*
X479881D01*
Y10384D01*
X479816D01*
Y10417D01*
X479687D01*
Y10449D01*
D02*
G37*
G36*
X495302Y-1004D02*
X490850D01*
Y-1036D01*
X490785D01*
Y-1068D01*
X490753D01*
Y-1101D01*
X490721D01*
Y-1133D01*
X490689D01*
Y-1165D01*
Y-1198D01*
Y-1230D01*
Y-1262D01*
Y-1294D01*
Y-1327D01*
Y-1359D01*
Y-1391D01*
Y-1423D01*
Y-1456D01*
Y-1488D01*
Y-1520D01*
Y-1552D01*
Y-1585D01*
Y-1617D01*
Y-1649D01*
Y-1681D01*
Y-1714D01*
Y-1746D01*
Y-1778D01*
Y-1811D01*
Y-1843D01*
Y-1875D01*
Y-1907D01*
Y-1940D01*
Y-1972D01*
Y-2004D01*
Y-2036D01*
Y-2069D01*
Y-2101D01*
Y-2133D01*
Y-2165D01*
Y-2198D01*
Y-2230D01*
Y-2262D01*
Y-2294D01*
Y-2327D01*
Y-2359D01*
Y-2391D01*
Y-2424D01*
Y-2456D01*
Y-2488D01*
Y-2520D01*
Y-2553D01*
Y-2585D01*
Y-2617D01*
Y-2649D01*
Y-2682D01*
Y-2714D01*
Y-2746D01*
Y-2778D01*
Y-2811D01*
Y-2843D01*
Y-2875D01*
Y-2907D01*
Y-2940D01*
Y-2972D01*
Y-3004D01*
Y-3036D01*
Y-3069D01*
Y-3101D01*
Y-3133D01*
Y-3165D01*
Y-3198D01*
Y-3230D01*
Y-3262D01*
Y-3295D01*
Y-3327D01*
Y-3359D01*
Y-3391D01*
Y-3424D01*
Y-3456D01*
Y-3488D01*
Y-3520D01*
Y-3553D01*
Y-3585D01*
Y-3617D01*
Y-3650D01*
Y-3682D01*
Y-3714D01*
Y-3746D01*
Y-3779D01*
Y-3811D01*
Y-3843D01*
Y-3875D01*
Y-3907D01*
Y-3940D01*
Y-3972D01*
Y-4004D01*
Y-4037D01*
Y-4069D01*
Y-4101D01*
Y-4133D01*
Y-4166D01*
Y-4198D01*
Y-4230D01*
Y-4262D01*
Y-4295D01*
Y-4327D01*
Y-4359D01*
Y-4391D01*
Y-4424D01*
Y-4456D01*
Y-4488D01*
Y-4521D01*
Y-4553D01*
Y-4585D01*
Y-4617D01*
Y-4650D01*
Y-4682D01*
Y-4714D01*
Y-4746D01*
Y-4779D01*
Y-4811D01*
Y-4843D01*
Y-4875D01*
Y-4908D01*
Y-4940D01*
Y-4972D01*
Y-5004D01*
Y-5037D01*
Y-5069D01*
Y-5101D01*
Y-5133D01*
Y-5166D01*
Y-5198D01*
Y-5230D01*
Y-5263D01*
Y-5295D01*
Y-5327D01*
Y-5359D01*
Y-5392D01*
Y-5424D01*
Y-5456D01*
Y-5488D01*
Y-5521D01*
Y-5553D01*
Y-5585D01*
Y-5617D01*
Y-5650D01*
Y-5682D01*
Y-5714D01*
Y-5746D01*
Y-5779D01*
Y-5811D01*
Y-5843D01*
Y-5875D01*
Y-5908D01*
Y-5940D01*
Y-5972D01*
Y-6005D01*
Y-6037D01*
Y-6069D01*
Y-6101D01*
Y-6134D01*
Y-6166D01*
Y-6198D01*
Y-6230D01*
Y-6263D01*
Y-6295D01*
Y-6327D01*
Y-6359D01*
Y-6392D01*
Y-6424D01*
Y-6456D01*
Y-6488D01*
Y-6521D01*
Y-6553D01*
Y-6585D01*
Y-6617D01*
Y-6650D01*
Y-6682D01*
Y-6714D01*
Y-6747D01*
Y-6779D01*
Y-6811D01*
Y-6843D01*
Y-6876D01*
Y-6908D01*
Y-6940D01*
Y-6972D01*
Y-7005D01*
Y-7037D01*
Y-7069D01*
Y-7102D01*
Y-7134D01*
Y-7166D01*
Y-7198D01*
Y-7231D01*
Y-7263D01*
Y-7295D01*
Y-7327D01*
Y-7360D01*
Y-7392D01*
Y-7424D01*
Y-7456D01*
Y-7489D01*
Y-7521D01*
Y-7553D01*
Y-7585D01*
Y-7618D01*
Y-7650D01*
Y-7682D01*
Y-7714D01*
Y-7747D01*
Y-7779D01*
Y-7811D01*
Y-7843D01*
Y-7876D01*
Y-7908D01*
Y-7940D01*
X490721D01*
Y-7972D01*
X490753D01*
Y-8005D01*
X490785D01*
Y-8037D01*
X495399D01*
Y-8005D01*
X495528D01*
Y-7972D01*
X495592D01*
Y-7940D01*
X495625D01*
Y-7908D01*
X495657D01*
Y-7876D01*
X495689D01*
Y-7843D01*
X495721D01*
Y-7811D01*
X495754D01*
Y-7779D01*
X495786D01*
Y-7747D01*
X495818D01*
Y-7714D01*
X495850D01*
Y-7682D01*
X495883D01*
Y-7650D01*
X495915D01*
Y-7618D01*
X495947D01*
Y-7585D01*
X495979D01*
Y-7553D01*
X496012D01*
Y-7521D01*
X496044D01*
Y-7489D01*
X496076D01*
Y-7456D01*
X496108D01*
Y-7424D01*
X496141D01*
Y-7392D01*
X496173D01*
Y-7360D01*
X496205D01*
Y-7327D01*
X496238D01*
Y-7295D01*
X496270D01*
Y-7263D01*
X496302D01*
Y-7231D01*
X496334D01*
Y-7198D01*
X496367D01*
Y-7166D01*
X496399D01*
Y-7134D01*
X496431D01*
Y-7102D01*
X496463D01*
Y-7069D01*
X496496D01*
Y-7037D01*
X496528D01*
Y-7005D01*
Y-6972D01*
Y-6940D01*
X496560D01*
Y-6908D01*
Y-6876D01*
Y-6843D01*
Y-6811D01*
X496592D01*
Y-6779D01*
Y-6747D01*
Y-6714D01*
Y-6682D01*
Y-6650D01*
Y-6617D01*
Y-6585D01*
Y-6553D01*
Y-6521D01*
Y-6488D01*
Y-6456D01*
Y-6424D01*
Y-6392D01*
Y-6359D01*
Y-6327D01*
Y-6295D01*
Y-6263D01*
Y-6230D01*
Y-6198D01*
Y-6166D01*
Y-6134D01*
Y-6101D01*
Y-6069D01*
Y-6037D01*
Y-6005D01*
Y-5972D01*
Y-5940D01*
Y-5908D01*
Y-5875D01*
Y-5843D01*
Y-5811D01*
Y-5779D01*
Y-5746D01*
Y-5714D01*
Y-5682D01*
Y-5650D01*
Y-5617D01*
Y-5585D01*
Y-5553D01*
Y-5521D01*
Y-5488D01*
Y-5456D01*
Y-5424D01*
Y-5392D01*
Y-5359D01*
Y-5327D01*
Y-5295D01*
Y-5263D01*
Y-5230D01*
Y-5198D01*
Y-5166D01*
Y-5133D01*
Y-5101D01*
Y-5069D01*
Y-5037D01*
Y-5004D01*
Y-4972D01*
Y-4940D01*
Y-4908D01*
Y-4875D01*
Y-4843D01*
Y-4811D01*
Y-4779D01*
Y-4746D01*
Y-4714D01*
Y-4682D01*
Y-4650D01*
Y-4617D01*
Y-4585D01*
Y-4553D01*
Y-4521D01*
Y-4488D01*
Y-4456D01*
Y-4424D01*
Y-4391D01*
Y-4359D01*
Y-4327D01*
Y-4295D01*
Y-4262D01*
Y-4230D01*
Y-4198D01*
Y-4166D01*
Y-4133D01*
Y-4101D01*
Y-4069D01*
Y-4037D01*
Y-4004D01*
Y-3972D01*
Y-3940D01*
Y-3907D01*
Y-3875D01*
Y-3843D01*
Y-3811D01*
Y-3779D01*
Y-3746D01*
Y-3714D01*
Y-3682D01*
Y-3650D01*
Y-3617D01*
Y-3585D01*
Y-3553D01*
Y-3520D01*
Y-3488D01*
Y-3456D01*
Y-3424D01*
Y-3391D01*
Y-3359D01*
Y-3327D01*
Y-3295D01*
Y-3262D01*
Y-3230D01*
Y-3198D01*
Y-3165D01*
Y-3133D01*
Y-3101D01*
Y-3069D01*
Y-3036D01*
Y-3004D01*
Y-2972D01*
Y-2940D01*
Y-2907D01*
Y-2875D01*
Y-2843D01*
Y-2811D01*
Y-2778D01*
Y-2746D01*
Y-2714D01*
Y-2682D01*
Y-2649D01*
Y-2617D01*
Y-2585D01*
Y-2553D01*
Y-2520D01*
Y-2488D01*
Y-2456D01*
Y-2424D01*
Y-2391D01*
Y-2359D01*
Y-2327D01*
Y-2294D01*
Y-2262D01*
Y-2230D01*
X496560D01*
Y-2198D01*
Y-2165D01*
Y-2133D01*
Y-2101D01*
X496528D01*
Y-2069D01*
Y-2036D01*
X496496D01*
Y-2004D01*
X496463D01*
Y-1972D01*
X496431D01*
Y-1940D01*
X496399D01*
Y-1907D01*
X496367D01*
Y-1875D01*
X496334D01*
Y-1843D01*
X496302D01*
Y-1811D01*
X496270D01*
Y-1778D01*
X496238D01*
Y-1746D01*
X496205D01*
Y-1714D01*
X496173D01*
Y-1681D01*
X496141D01*
Y-1649D01*
X496108D01*
Y-1617D01*
X496076D01*
Y-1585D01*
X496044D01*
Y-1552D01*
X496012D01*
Y-1520D01*
X495979D01*
Y-1488D01*
X495947D01*
Y-1456D01*
X495915D01*
Y-1423D01*
X495883D01*
Y-1391D01*
X495850D01*
Y-1359D01*
X495818D01*
Y-1327D01*
X495786D01*
Y-1294D01*
X495754D01*
Y-1262D01*
X495721D01*
Y-1230D01*
X495689D01*
Y-1198D01*
X495657D01*
Y-1165D01*
X495625D01*
Y-1133D01*
X495592D01*
Y-1101D01*
X495560D01*
Y-1068D01*
X495463D01*
Y-1036D01*
X495302D01*
Y-1004D01*
D02*
G37*
G36*
X488430D02*
X483978D01*
Y-1036D01*
X483914D01*
Y-1068D01*
X483881D01*
Y-1101D01*
X483849D01*
Y-1133D01*
Y-1165D01*
Y-1198D01*
X483817D01*
Y-1230D01*
Y-1262D01*
Y-1294D01*
Y-1327D01*
Y-1359D01*
Y-1391D01*
Y-1423D01*
Y-1456D01*
Y-1488D01*
Y-1520D01*
Y-1552D01*
Y-1585D01*
Y-1617D01*
Y-1649D01*
Y-1681D01*
Y-1714D01*
Y-1746D01*
Y-1778D01*
Y-1811D01*
Y-1843D01*
Y-1875D01*
Y-1907D01*
Y-1940D01*
Y-1972D01*
Y-2004D01*
Y-2036D01*
Y-2069D01*
Y-2101D01*
Y-2133D01*
Y-2165D01*
Y-2198D01*
Y-2230D01*
Y-2262D01*
Y-2294D01*
Y-2327D01*
Y-2359D01*
Y-2391D01*
Y-2424D01*
Y-2456D01*
Y-2488D01*
Y-2520D01*
Y-2553D01*
Y-2585D01*
Y-2617D01*
Y-2649D01*
Y-2682D01*
Y-2714D01*
Y-2746D01*
Y-2778D01*
Y-2811D01*
Y-2843D01*
Y-2875D01*
Y-2907D01*
Y-2940D01*
Y-2972D01*
Y-3004D01*
Y-3036D01*
Y-3069D01*
Y-3101D01*
Y-3133D01*
Y-3165D01*
Y-3198D01*
Y-3230D01*
Y-3262D01*
Y-3295D01*
Y-3327D01*
Y-3359D01*
Y-3391D01*
Y-3424D01*
Y-3456D01*
Y-3488D01*
Y-3520D01*
Y-3553D01*
Y-3585D01*
Y-3617D01*
Y-3650D01*
Y-3682D01*
Y-3714D01*
Y-3746D01*
Y-3779D01*
Y-3811D01*
Y-3843D01*
Y-3875D01*
Y-3907D01*
Y-3940D01*
Y-3972D01*
Y-4004D01*
Y-4037D01*
Y-4069D01*
Y-4101D01*
Y-4133D01*
Y-4166D01*
Y-4198D01*
Y-4230D01*
Y-4262D01*
Y-4295D01*
Y-4327D01*
Y-4359D01*
Y-4391D01*
Y-4424D01*
Y-4456D01*
Y-4488D01*
Y-4521D01*
Y-4553D01*
Y-4585D01*
Y-4617D01*
Y-4650D01*
Y-4682D01*
Y-4714D01*
Y-4746D01*
Y-4779D01*
Y-4811D01*
Y-4843D01*
Y-4875D01*
Y-4908D01*
Y-4940D01*
Y-4972D01*
Y-5004D01*
Y-5037D01*
Y-5069D01*
Y-5101D01*
Y-5133D01*
Y-5166D01*
Y-5198D01*
Y-5230D01*
Y-5263D01*
Y-5295D01*
Y-5327D01*
Y-5359D01*
Y-5392D01*
Y-5424D01*
Y-5456D01*
Y-5488D01*
Y-5521D01*
Y-5553D01*
Y-5585D01*
Y-5617D01*
Y-5650D01*
Y-5682D01*
Y-5714D01*
Y-5746D01*
Y-5779D01*
Y-5811D01*
Y-5843D01*
Y-5875D01*
Y-5908D01*
Y-5940D01*
Y-5972D01*
Y-6005D01*
Y-6037D01*
Y-6069D01*
Y-6101D01*
Y-6134D01*
Y-6166D01*
Y-6198D01*
Y-6230D01*
Y-6263D01*
Y-6295D01*
Y-6327D01*
Y-6359D01*
Y-6392D01*
Y-6424D01*
Y-6456D01*
Y-6488D01*
Y-6521D01*
Y-6553D01*
Y-6585D01*
Y-6617D01*
Y-6650D01*
Y-6682D01*
Y-6714D01*
Y-6747D01*
Y-6779D01*
Y-6811D01*
Y-6843D01*
Y-6876D01*
Y-6908D01*
Y-6940D01*
Y-6972D01*
Y-7005D01*
Y-7037D01*
Y-7069D01*
Y-7102D01*
Y-7134D01*
Y-7166D01*
Y-7198D01*
Y-7231D01*
Y-7263D01*
Y-7295D01*
Y-7327D01*
Y-7360D01*
Y-7392D01*
Y-7424D01*
Y-7456D01*
Y-7489D01*
Y-7521D01*
Y-7553D01*
Y-7585D01*
Y-7618D01*
Y-7650D01*
Y-7682D01*
Y-7714D01*
Y-7747D01*
Y-7779D01*
Y-7811D01*
X483849D01*
Y-7843D01*
X483817D01*
Y-7876D01*
X483849D01*
Y-7908D01*
Y-7940D01*
Y-7972D01*
X483881D01*
Y-8005D01*
X483946D01*
Y-8037D01*
X485527D01*
Y-8005D01*
X485559D01*
Y-7972D01*
X485591D01*
Y-7940D01*
Y-7908D01*
Y-7876D01*
X485623D01*
Y-7843D01*
Y-7811D01*
Y-7779D01*
Y-7747D01*
Y-7714D01*
Y-7682D01*
Y-7650D01*
Y-7618D01*
Y-7585D01*
Y-7553D01*
Y-7521D01*
Y-7489D01*
Y-7456D01*
Y-7424D01*
Y-7392D01*
Y-7360D01*
Y-7327D01*
Y-7295D01*
Y-7263D01*
Y-7231D01*
Y-7198D01*
Y-7166D01*
Y-7134D01*
Y-7102D01*
Y-7069D01*
Y-7037D01*
Y-7005D01*
Y-6972D01*
Y-6940D01*
Y-6908D01*
Y-6876D01*
Y-6843D01*
Y-6811D01*
Y-6779D01*
Y-6747D01*
Y-6714D01*
Y-6682D01*
Y-6650D01*
Y-6617D01*
Y-6585D01*
Y-6553D01*
Y-6521D01*
Y-6488D01*
Y-6456D01*
Y-6424D01*
Y-6392D01*
Y-6359D01*
Y-6327D01*
Y-6295D01*
Y-6263D01*
Y-6230D01*
Y-6198D01*
Y-6166D01*
Y-6134D01*
X485591D01*
Y-6101D01*
X485623D01*
Y-6069D01*
Y-6037D01*
Y-6005D01*
Y-5972D01*
Y-5940D01*
X486849D01*
Y-5972D01*
Y-6005D01*
X486882D01*
Y-6037D01*
Y-6069D01*
X486914D01*
Y-6101D01*
X486946D01*
Y-6134D01*
Y-6166D01*
X486978D01*
Y-6198D01*
Y-6230D01*
X487011D01*
Y-6263D01*
X487043D01*
Y-6295D01*
Y-6327D01*
X487075D01*
Y-6359D01*
Y-6392D01*
X487108D01*
Y-6424D01*
Y-6456D01*
X487140D01*
Y-6488D01*
X487172D01*
Y-6521D01*
Y-6553D01*
X487204D01*
Y-6585D01*
Y-6617D01*
X487236D01*
Y-6650D01*
X487269D01*
Y-6682D01*
Y-6714D01*
X487301D01*
Y-6747D01*
Y-6779D01*
X487333D01*
Y-6811D01*
X487366D01*
Y-6843D01*
Y-6876D01*
X487398D01*
Y-6908D01*
Y-6940D01*
X487430D01*
Y-6972D01*
Y-7005D01*
X487462D01*
Y-7037D01*
X487495D01*
Y-7069D01*
Y-7102D01*
X487527D01*
Y-7134D01*
Y-7166D01*
X487559D01*
Y-7198D01*
X487591D01*
Y-7231D01*
Y-7263D01*
X487624D01*
Y-7295D01*
Y-7327D01*
X487656D01*
Y-7360D01*
X487688D01*
Y-7392D01*
Y-7424D01*
X487720D01*
Y-7456D01*
Y-7489D01*
X487753D01*
Y-7521D01*
X487785D01*
Y-7553D01*
Y-7585D01*
X487817D01*
Y-7618D01*
Y-7650D01*
X487850D01*
Y-7682D01*
Y-7714D01*
X487882D01*
Y-7747D01*
X487914D01*
Y-7779D01*
Y-7811D01*
X487946D01*
Y-7843D01*
Y-7876D01*
X487979D01*
Y-7908D01*
X488011D01*
Y-7940D01*
X488043D01*
Y-7972D01*
X488075D01*
Y-8005D01*
X488140D01*
Y-8037D01*
X489947D01*
Y-8005D01*
X489979D01*
Y-7972D01*
Y-7940D01*
Y-7908D01*
Y-7876D01*
X489947D01*
Y-7843D01*
X489914D01*
Y-7811D01*
Y-7779D01*
X489882D01*
Y-7747D01*
Y-7714D01*
X489850D01*
Y-7682D01*
X489817D01*
Y-7650D01*
Y-7618D01*
X489785D01*
Y-7585D01*
Y-7553D01*
X489753D01*
Y-7521D01*
X489721D01*
Y-7489D01*
Y-7456D01*
X489688D01*
Y-7424D01*
Y-7392D01*
X489656D01*
Y-7360D01*
X489624D01*
Y-7327D01*
Y-7295D01*
X489592D01*
Y-7263D01*
Y-7231D01*
X489559D01*
Y-7198D01*
X489527D01*
Y-7166D01*
Y-7134D01*
X489495D01*
Y-7102D01*
Y-7069D01*
X489463D01*
Y-7037D01*
X489430D01*
Y-7005D01*
Y-6972D01*
X489398D01*
Y-6940D01*
Y-6908D01*
X489366D01*
Y-6876D01*
X489333D01*
Y-6843D01*
Y-6811D01*
X489301D01*
Y-6779D01*
Y-6747D01*
X489269D01*
Y-6714D01*
X489237D01*
Y-6682D01*
Y-6650D01*
X489205D01*
Y-6617D01*
Y-6585D01*
X489172D01*
Y-6553D01*
X489140D01*
Y-6521D01*
Y-6488D01*
X489108D01*
Y-6456D01*
Y-6424D01*
X489076D01*
Y-6392D01*
X489043D01*
Y-6359D01*
Y-6327D01*
X489011D01*
Y-6295D01*
Y-6263D01*
X488979D01*
Y-6230D01*
X488946D01*
Y-6198D01*
Y-6166D01*
X488914D01*
Y-6134D01*
Y-6101D01*
X488882D01*
Y-6069D01*
Y-6037D01*
X488850D01*
Y-6005D01*
X488817D01*
Y-5972D01*
Y-5940D01*
X488785D01*
Y-5908D01*
Y-5875D01*
X488753D01*
Y-5843D01*
X488721D01*
Y-5811D01*
Y-5779D01*
X488753D01*
Y-5746D01*
X488785D01*
Y-5714D01*
X488817D01*
Y-5682D01*
X488850D01*
Y-5650D01*
X488882D01*
Y-5617D01*
X488914D01*
Y-5585D01*
X488946D01*
Y-5553D01*
X488979D01*
Y-5521D01*
X489011D01*
Y-5488D01*
X489043D01*
Y-5456D01*
X489076D01*
Y-5424D01*
X489108D01*
Y-5392D01*
X489140D01*
Y-5359D01*
X489172D01*
Y-5327D01*
X489205D01*
Y-5295D01*
X489237D01*
Y-5263D01*
X489269D01*
Y-5230D01*
X489301D01*
Y-5198D01*
X489333D01*
Y-5166D01*
X489366D01*
Y-5133D01*
X489398D01*
Y-5101D01*
X489430D01*
Y-5069D01*
X489463D01*
Y-5037D01*
Y-5004D01*
X489495D01*
Y-4972D01*
X489527D01*
Y-4940D01*
X489559D01*
Y-4908D01*
X489592D01*
Y-4875D01*
X489624D01*
Y-4843D01*
X489656D01*
Y-4811D01*
Y-4779D01*
X489688D01*
Y-4746D01*
Y-4714D01*
X489721D01*
Y-4682D01*
Y-4650D01*
Y-4617D01*
Y-4585D01*
Y-4553D01*
Y-4521D01*
Y-4488D01*
Y-4456D01*
Y-4424D01*
Y-4391D01*
Y-4359D01*
Y-4327D01*
Y-4295D01*
Y-4262D01*
Y-4230D01*
Y-4198D01*
Y-4166D01*
Y-4133D01*
Y-4101D01*
Y-4069D01*
Y-4037D01*
Y-4004D01*
Y-3972D01*
Y-3940D01*
Y-3907D01*
Y-3875D01*
Y-3843D01*
Y-3811D01*
Y-3779D01*
Y-3746D01*
Y-3714D01*
Y-3682D01*
Y-3650D01*
Y-3617D01*
Y-3585D01*
Y-3553D01*
Y-3520D01*
Y-3488D01*
Y-3456D01*
Y-3424D01*
Y-3391D01*
Y-3359D01*
Y-3327D01*
Y-3295D01*
Y-3262D01*
Y-3230D01*
Y-3198D01*
Y-3165D01*
Y-3133D01*
Y-3101D01*
Y-3069D01*
Y-3036D01*
Y-3004D01*
Y-2972D01*
Y-2940D01*
Y-2907D01*
Y-2875D01*
Y-2843D01*
Y-2811D01*
Y-2778D01*
Y-2746D01*
Y-2714D01*
Y-2682D01*
Y-2649D01*
Y-2617D01*
Y-2585D01*
Y-2553D01*
Y-2520D01*
Y-2488D01*
Y-2456D01*
Y-2424D01*
Y-2391D01*
Y-2359D01*
Y-2327D01*
Y-2294D01*
Y-2262D01*
Y-2230D01*
Y-2198D01*
Y-2165D01*
X489688D01*
Y-2133D01*
Y-2101D01*
Y-2069D01*
X489656D01*
Y-2036D01*
Y-2004D01*
X489624D01*
Y-1972D01*
X489592D01*
Y-1940D01*
X489559D01*
Y-1907D01*
X489527D01*
Y-1875D01*
X489495D01*
Y-1843D01*
X489463D01*
Y-1811D01*
X489430D01*
Y-1778D01*
X489398D01*
Y-1746D01*
X489366D01*
Y-1714D01*
X489333D01*
Y-1681D01*
X489301D01*
Y-1649D01*
X489269D01*
Y-1617D01*
X489237D01*
Y-1585D01*
X489205D01*
Y-1552D01*
X489172D01*
Y-1520D01*
X489140D01*
Y-1488D01*
X489108D01*
Y-1456D01*
X489076D01*
Y-1423D01*
X489043D01*
Y-1391D01*
X489011D01*
Y-1359D01*
X488979D01*
Y-1327D01*
X488946D01*
Y-1294D01*
X488914D01*
Y-1262D01*
X488882D01*
Y-1230D01*
X488850D01*
Y-1198D01*
X488817D01*
Y-1165D01*
X488785D01*
Y-1133D01*
X488753D01*
Y-1101D01*
X488688D01*
Y-1068D01*
X488591D01*
Y-1036D01*
X488430D01*
Y-1004D01*
D02*
G37*
G36*
X468105Y-1036D02*
X467718D01*
Y-1068D01*
Y-1101D01*
Y-1133D01*
Y-1165D01*
Y-1198D01*
Y-1230D01*
Y-1262D01*
Y-1294D01*
Y-1327D01*
Y-1359D01*
Y-1391D01*
X467750D01*
Y-1423D01*
Y-1456D01*
Y-1488D01*
Y-1520D01*
Y-1552D01*
Y-1585D01*
Y-1617D01*
Y-1649D01*
Y-1681D01*
Y-1714D01*
Y-1746D01*
X467783D01*
Y-1778D01*
X467750D01*
Y-1811D01*
X467783D01*
Y-1843D01*
Y-1875D01*
Y-1907D01*
Y-1940D01*
Y-1972D01*
Y-2004D01*
Y-2036D01*
Y-2069D01*
Y-2101D01*
Y-2133D01*
X467815D01*
Y-2165D01*
Y-2198D01*
Y-2230D01*
Y-2262D01*
Y-2294D01*
Y-2327D01*
Y-2359D01*
Y-2391D01*
X467847D01*
Y-2424D01*
Y-2456D01*
Y-2488D01*
Y-2520D01*
Y-2553D01*
Y-2585D01*
Y-2617D01*
X467879D01*
Y-2649D01*
Y-2682D01*
Y-2714D01*
Y-2746D01*
Y-2778D01*
Y-2811D01*
X467912D01*
Y-2843D01*
Y-2875D01*
Y-2907D01*
Y-2940D01*
Y-2972D01*
X467944D01*
Y-3004D01*
Y-3036D01*
Y-3069D01*
Y-3101D01*
Y-3133D01*
X467976D01*
Y-3165D01*
Y-3198D01*
Y-3230D01*
Y-3262D01*
Y-3295D01*
X468009D01*
Y-3327D01*
Y-3359D01*
Y-3391D01*
Y-3424D01*
Y-3456D01*
X468041D01*
Y-3488D01*
Y-3520D01*
Y-3553D01*
Y-3585D01*
X468073D01*
Y-3617D01*
Y-3650D01*
Y-3682D01*
Y-3714D01*
X468105D01*
Y-3746D01*
Y-3779D01*
Y-3811D01*
Y-3843D01*
X468138D01*
Y-3875D01*
Y-3907D01*
Y-3940D01*
Y-3972D01*
X468170D01*
Y-4004D01*
Y-4037D01*
Y-4069D01*
X468202D01*
Y-4101D01*
Y-4133D01*
Y-4166D01*
Y-4198D01*
X468234D01*
Y-4230D01*
Y-4262D01*
Y-4295D01*
X468267D01*
Y-4327D01*
Y-4359D01*
Y-4391D01*
X468299D01*
Y-4424D01*
Y-4456D01*
Y-4488D01*
X468331D01*
Y-4521D01*
Y-4553D01*
Y-4585D01*
X468363D01*
Y-4617D01*
Y-4650D01*
Y-4682D01*
X468396D01*
Y-4714D01*
Y-4746D01*
Y-4779D01*
X468428D01*
Y-4811D01*
Y-4843D01*
Y-4875D01*
X468460D01*
Y-4908D01*
Y-4940D01*
Y-4972D01*
X468492D01*
Y-5004D01*
Y-5037D01*
Y-5069D01*
X468525D01*
Y-5101D01*
Y-5133D01*
X468557D01*
Y-5166D01*
Y-5198D01*
Y-5230D01*
X468589D01*
Y-5263D01*
Y-5295D01*
X468621D01*
Y-5327D01*
Y-5359D01*
Y-5392D01*
X468654D01*
Y-5424D01*
Y-5456D01*
X468686D01*
Y-5488D01*
Y-5521D01*
Y-5553D01*
X468718D01*
Y-5585D01*
Y-5617D01*
X468750D01*
Y-5650D01*
Y-5682D01*
X468783D01*
Y-5714D01*
Y-5746D01*
Y-5779D01*
X468815D01*
Y-5811D01*
Y-5843D01*
X468847D01*
Y-5875D01*
Y-5908D01*
X468880D01*
Y-5940D01*
Y-5972D01*
X468912D01*
Y-6005D01*
Y-6037D01*
X468944D01*
Y-6069D01*
Y-6101D01*
X468976D01*
Y-6134D01*
Y-6166D01*
X469009D01*
Y-6198D01*
Y-6230D01*
X469041D01*
Y-6263D01*
Y-6295D01*
X469073D01*
Y-6327D01*
Y-6359D01*
X469105D01*
Y-6392D01*
Y-6424D01*
X469138D01*
Y-6456D01*
Y-6488D01*
X469170D01*
Y-6521D01*
Y-6553D01*
X469202D01*
Y-6585D01*
Y-6617D01*
X469235D01*
Y-6650D01*
X469267D01*
Y-6682D01*
Y-6714D01*
X469299D01*
Y-6747D01*
Y-6779D01*
X469331D01*
Y-6811D01*
Y-6843D01*
X469363D01*
Y-6876D01*
Y-6908D01*
X469396D01*
Y-6940D01*
X469428D01*
Y-6972D01*
Y-7005D01*
X469460D01*
Y-7037D01*
Y-7069D01*
X469492D01*
Y-7102D01*
Y-7134D01*
X469525D01*
Y-7166D01*
X469557D01*
Y-7198D01*
Y-7231D01*
X469589D01*
Y-7263D01*
X469622D01*
Y-7295D01*
Y-7327D01*
X469654D01*
Y-7360D01*
Y-7392D01*
X469686D01*
Y-7424D01*
X469718D01*
Y-7456D01*
Y-7489D01*
X469751D01*
Y-7521D01*
X469783D01*
Y-7553D01*
Y-7585D01*
X469815D01*
Y-7618D01*
X469847D01*
Y-7650D01*
Y-7682D01*
X469880D01*
Y-7714D01*
X469912D01*
Y-7747D01*
Y-7779D01*
X469944D01*
Y-7811D01*
X469977D01*
Y-7843D01*
X470009D01*
Y-7876D01*
Y-7908D01*
X470041D01*
Y-7940D01*
X470073D01*
Y-7972D01*
Y-8005D01*
X470106D01*
Y-8037D01*
X470138D01*
Y-8069D01*
X470170D01*
Y-8102D01*
Y-8134D01*
X470202D01*
Y-8166D01*
X470235D01*
Y-8198D01*
X470267D01*
Y-8231D01*
Y-8263D01*
X470299D01*
Y-8295D01*
X470331D01*
Y-8327D01*
X470364D01*
Y-8360D01*
X470396D01*
Y-8392D01*
Y-8424D01*
X470428D01*
Y-8456D01*
X470460D01*
Y-8489D01*
X470493D01*
Y-8521D01*
X470525D01*
Y-8553D01*
Y-8585D01*
X470557D01*
Y-8618D01*
X470589D01*
Y-8650D01*
X470622D01*
Y-8682D01*
X470654D01*
Y-8715D01*
Y-8747D01*
X470686D01*
Y-8779D01*
X470718D01*
Y-8811D01*
X470751D01*
Y-8844D01*
X470783D01*
Y-8876D01*
X470815D01*
Y-8908D01*
X470848D01*
Y-8940D01*
X470880D01*
Y-8973D01*
Y-9005D01*
X470912D01*
Y-9037D01*
X470944D01*
Y-9069D01*
X470977D01*
Y-9102D01*
X471009D01*
Y-9134D01*
X471041D01*
Y-9166D01*
X471073D01*
Y-9199D01*
X471106D01*
Y-9231D01*
X471138D01*
Y-9263D01*
X471170D01*
Y-9295D01*
X471202D01*
Y-9328D01*
X471235D01*
Y-9360D01*
X471267D01*
Y-9392D01*
X471299D01*
Y-9424D01*
X471332D01*
Y-9457D01*
X471364D01*
Y-9489D01*
X471396D01*
Y-9521D01*
X471428D01*
Y-9553D01*
X471460D01*
Y-9586D01*
X471493D01*
Y-9618D01*
X471525D01*
Y-9650D01*
X471557D01*
Y-9682D01*
X471590D01*
Y-9715D01*
X471622D01*
Y-9747D01*
X471654D01*
Y-9779D01*
X471686D01*
Y-9811D01*
X471719D01*
Y-9844D01*
X471751D01*
Y-9876D01*
X471783D01*
Y-9908D01*
X471815D01*
Y-9940D01*
X471848D01*
Y-9973D01*
X471912D01*
Y-10005D01*
X471944D01*
Y-10037D01*
X471977D01*
Y-10069D01*
X472009D01*
Y-10102D01*
X472041D01*
Y-10134D01*
X472074D01*
Y-10166D01*
X472106D01*
Y-10199D01*
X472170D01*
Y-10231D01*
X472202D01*
Y-10263D01*
X472235D01*
Y-10295D01*
X472267D01*
Y-10328D01*
X472299D01*
Y-10360D01*
X472364D01*
Y-10392D01*
X472396D01*
Y-10424D01*
X472428D01*
Y-10457D01*
X472461D01*
Y-10489D01*
X472525D01*
Y-10521D01*
X472557D01*
Y-10554D01*
X472590D01*
Y-10586D01*
X472654D01*
Y-10618D01*
X472686D01*
Y-10650D01*
X472719D01*
Y-10683D01*
X472783D01*
Y-10715D01*
X472816D01*
Y-10747D01*
X472848D01*
Y-10779D01*
X472912D01*
Y-10812D01*
X472944D01*
Y-10844D01*
X473009D01*
Y-10876D01*
X473041D01*
Y-10908D01*
X473074D01*
Y-10941D01*
X473138D01*
Y-10973D01*
X473170D01*
Y-11005D01*
X473235D01*
Y-11037D01*
X473267D01*
Y-11070D01*
X473332D01*
Y-11102D01*
X473364D01*
Y-11134D01*
X473428D01*
Y-11167D01*
X473461D01*
Y-11199D01*
X473525D01*
Y-11231D01*
X473590D01*
Y-11263D01*
X473622D01*
Y-11295D01*
X473687D01*
Y-11328D01*
X473719D01*
Y-11360D01*
X473783D01*
Y-11392D01*
X473848D01*
Y-11425D01*
X473880D01*
Y-11457D01*
X473945D01*
Y-11489D01*
X474009D01*
Y-11521D01*
X474074D01*
Y-11554D01*
X474106D01*
Y-11586D01*
X474170D01*
Y-11618D01*
X474235D01*
Y-11650D01*
X474299D01*
Y-11683D01*
X474364D01*
Y-11715D01*
X474429D01*
Y-11747D01*
X474493D01*
Y-11779D01*
X474558D01*
Y-11812D01*
X474622D01*
Y-11844D01*
X474687D01*
Y-11876D01*
X474751D01*
Y-11908D01*
X474816D01*
Y-11941D01*
X474880D01*
Y-11973D01*
X474945D01*
Y-12005D01*
X475009D01*
Y-12037D01*
X475074D01*
Y-12070D01*
X475171D01*
Y-12102D01*
X475235D01*
Y-12134D01*
X475300D01*
Y-12167D01*
X475396D01*
Y-12199D01*
X475461D01*
Y-12231D01*
X475558D01*
Y-12263D01*
X475622D01*
Y-12296D01*
X475719D01*
Y-12328D01*
X475784D01*
Y-12360D01*
X475880D01*
Y-12392D01*
X475977D01*
Y-12425D01*
X476074D01*
Y-12457D01*
X476138D01*
Y-12489D01*
X476235D01*
Y-12521D01*
X476332D01*
Y-12554D01*
X476461D01*
Y-12586D01*
X476558D01*
Y-12618D01*
X476655D01*
Y-12651D01*
X476784D01*
Y-12683D01*
X476881D01*
Y-12715D01*
X477009D01*
Y-12747D01*
X477139D01*
Y-12780D01*
X477268D01*
Y-12812D01*
X477397D01*
Y-12844D01*
X477558D01*
Y-12876D01*
X477687D01*
Y-12909D01*
X477848D01*
Y-12941D01*
X478042D01*
Y-12973D01*
X478235D01*
Y-13005D01*
X478461D01*
Y-13038D01*
X478687D01*
Y-13070D01*
X479010D01*
Y-13102D01*
X479397D01*
Y-13134D01*
X480945D01*
Y-13102D01*
X481365D01*
Y-13070D01*
X481655D01*
Y-13038D01*
X481913D01*
Y-13005D01*
X482139D01*
Y-12973D01*
X482333D01*
Y-12941D01*
X482494D01*
Y-12909D01*
X482688D01*
Y-12876D01*
X482817D01*
Y-12844D01*
X482946D01*
Y-12812D01*
X483107D01*
Y-12780D01*
X483236D01*
Y-12747D01*
X483365D01*
Y-12715D01*
X483494D01*
Y-12683D01*
X483591D01*
Y-12651D01*
X483720D01*
Y-12618D01*
X483817D01*
Y-12586D01*
X483914D01*
Y-12554D01*
X484010D01*
Y-12521D01*
X484107D01*
Y-12489D01*
X484204D01*
Y-12457D01*
X484301D01*
Y-12425D01*
X484398D01*
Y-12392D01*
X484494D01*
Y-12360D01*
X484591D01*
Y-12328D01*
X484656D01*
Y-12296D01*
X484752D01*
Y-12263D01*
X484817D01*
Y-12231D01*
X484914D01*
Y-12199D01*
X484978D01*
Y-12167D01*
X485075D01*
Y-12134D01*
X485140D01*
Y-12102D01*
X485204D01*
Y-12070D01*
X485301D01*
Y-12037D01*
X485365D01*
Y-12005D01*
X485430D01*
Y-11973D01*
X485494D01*
Y-11941D01*
X485559D01*
Y-11908D01*
X485623D01*
Y-11876D01*
X485688D01*
Y-11844D01*
X485752D01*
Y-11812D01*
X485817D01*
Y-11779D01*
X485882D01*
Y-11747D01*
X485946D01*
Y-11715D01*
X486011D01*
Y-11683D01*
X486075D01*
Y-11650D01*
X486140D01*
Y-11618D01*
X486204D01*
Y-11586D01*
X486236D01*
Y-11554D01*
X486301D01*
Y-11521D01*
X486366D01*
Y-11489D01*
X486430D01*
Y-11457D01*
X486462D01*
Y-11425D01*
X486527D01*
Y-11392D01*
X486591D01*
Y-11360D01*
X486623D01*
Y-11328D01*
X486688D01*
Y-11295D01*
X486753D01*
Y-11263D01*
X486785D01*
Y-11231D01*
X486849D01*
Y-11199D01*
X486882D01*
Y-11167D01*
X486946D01*
Y-11134D01*
X487011D01*
Y-11102D01*
X487043D01*
Y-11070D01*
X487108D01*
Y-11037D01*
X487140D01*
Y-11005D01*
X487204D01*
Y-10973D01*
X487236D01*
Y-10941D01*
X487269D01*
Y-10908D01*
X487333D01*
Y-10876D01*
X487366D01*
Y-10844D01*
X487430D01*
Y-10812D01*
X487462D01*
Y-10779D01*
X487527D01*
Y-10747D01*
X487559D01*
Y-10715D01*
X487591D01*
Y-10683D01*
X487656D01*
Y-10650D01*
X487688D01*
Y-10618D01*
X487720D01*
Y-10586D01*
X487785D01*
Y-10554D01*
X487817D01*
Y-10521D01*
X487850D01*
Y-10489D01*
X487882D01*
Y-10457D01*
X487946D01*
Y-10424D01*
X487979D01*
Y-10392D01*
X488011D01*
Y-10360D01*
X488043D01*
Y-10328D01*
X488108D01*
Y-10295D01*
X488140D01*
Y-10263D01*
X488172D01*
Y-10231D01*
X488204D01*
Y-10199D01*
X488237D01*
Y-10166D01*
X488301D01*
Y-10134D01*
X488333D01*
Y-10102D01*
X488366D01*
Y-10069D01*
X488398D01*
Y-10037D01*
X488430D01*
Y-10005D01*
X488462D01*
Y-9973D01*
X488495D01*
Y-9940D01*
X488559D01*
Y-9908D01*
X488591D01*
Y-9876D01*
X488624D01*
Y-9844D01*
X488656D01*
Y-9811D01*
X488688D01*
Y-9779D01*
X488721D01*
Y-9747D01*
X488753D01*
Y-9715D01*
X488785D01*
Y-9682D01*
X488817D01*
Y-9650D01*
X488850D01*
Y-9618D01*
X488882D01*
Y-9586D01*
X488914D01*
Y-9553D01*
X488946D01*
Y-9521D01*
X488979D01*
Y-9489D01*
X489011D01*
Y-9457D01*
X489043D01*
Y-9424D01*
X489076D01*
Y-9392D01*
X489108D01*
Y-9360D01*
X489140D01*
Y-9328D01*
X489172D01*
Y-9295D01*
X489205D01*
Y-9263D01*
X489237D01*
Y-9231D01*
X489269D01*
Y-9199D01*
X489301D01*
Y-9166D01*
X489333D01*
Y-9134D01*
X489366D01*
Y-9102D01*
X489398D01*
Y-9069D01*
X489430D01*
Y-9037D01*
X489463D01*
Y-9005D01*
Y-8973D01*
X489495D01*
Y-8940D01*
X489527D01*
Y-8908D01*
X489559D01*
Y-8876D01*
X489592D01*
Y-8844D01*
X489624D01*
Y-8811D01*
X489656D01*
Y-8779D01*
X489688D01*
Y-8747D01*
Y-8715D01*
X489721D01*
Y-8682D01*
X489205D01*
Y-8715D01*
X489172D01*
Y-8747D01*
X489140D01*
Y-8779D01*
Y-8811D01*
X489108D01*
Y-8844D01*
X489076D01*
Y-8876D01*
X489043D01*
Y-8908D01*
X489011D01*
Y-8940D01*
X488979D01*
Y-8973D01*
X488946D01*
Y-9005D01*
X488914D01*
Y-9037D01*
X488882D01*
Y-9069D01*
X488850D01*
Y-9102D01*
X488817D01*
Y-9134D01*
X488785D01*
Y-9166D01*
X488753D01*
Y-9199D01*
X488721D01*
Y-9231D01*
X488688D01*
Y-9263D01*
X488656D01*
Y-9295D01*
X488624D01*
Y-9328D01*
X488591D01*
Y-9360D01*
X488559D01*
Y-9392D01*
X488527D01*
Y-9424D01*
X488495D01*
Y-9457D01*
X488462D01*
Y-9489D01*
X488430D01*
Y-9521D01*
X488398D01*
Y-9553D01*
X488366D01*
Y-9586D01*
X488333D01*
Y-9618D01*
X488269D01*
Y-9650D01*
X488237D01*
Y-9682D01*
X488204D01*
Y-9715D01*
X488172D01*
Y-9747D01*
X488140D01*
Y-9779D01*
X488108D01*
Y-9811D01*
X488075D01*
Y-9844D01*
X488011D01*
Y-9876D01*
X487979D01*
Y-9908D01*
X487946D01*
Y-9940D01*
X487914D01*
Y-9973D01*
X487882D01*
Y-10005D01*
X487817D01*
Y-10037D01*
X487785D01*
Y-10069D01*
X487753D01*
Y-10102D01*
X487720D01*
Y-10134D01*
X487656D01*
Y-10166D01*
X487624D01*
Y-10199D01*
X487591D01*
Y-10231D01*
X487559D01*
Y-10263D01*
X487495D01*
Y-10295D01*
X487462D01*
Y-10328D01*
X487430D01*
Y-10360D01*
X487366D01*
Y-10392D01*
X487333D01*
Y-10424D01*
X487301D01*
Y-10457D01*
X487236D01*
Y-10489D01*
X487204D01*
Y-10521D01*
X487140D01*
Y-10554D01*
X487108D01*
Y-10586D01*
X487075D01*
Y-10618D01*
X487011D01*
Y-10650D01*
X486978D01*
Y-10683D01*
X486914D01*
Y-10715D01*
X486882D01*
Y-10747D01*
X486817D01*
Y-10779D01*
X486785D01*
Y-10812D01*
X486720D01*
Y-10844D01*
X486688D01*
Y-10876D01*
X486623D01*
Y-10908D01*
X486559D01*
Y-10941D01*
X486527D01*
Y-10973D01*
X486462D01*
Y-11005D01*
X486398D01*
Y-11037D01*
X486366D01*
Y-11070D01*
X486301D01*
Y-11102D01*
X486236D01*
Y-11134D01*
X486204D01*
Y-11167D01*
X486140D01*
Y-11199D01*
X486075D01*
Y-11231D01*
X486011D01*
Y-11263D01*
X485978D01*
Y-11295D01*
X485914D01*
Y-11328D01*
X485849D01*
Y-11360D01*
X485785D01*
Y-11392D01*
X485720D01*
Y-11425D01*
X485656D01*
Y-11457D01*
X485591D01*
Y-11489D01*
X485527D01*
Y-11521D01*
X485462D01*
Y-11554D01*
X485398D01*
Y-11586D01*
X485333D01*
Y-11618D01*
X485269D01*
Y-11650D01*
X485204D01*
Y-11683D01*
X485140D01*
Y-11715D01*
X485043D01*
Y-11747D01*
X484978D01*
Y-11779D01*
X484881D01*
Y-11812D01*
X484817D01*
Y-11844D01*
X484752D01*
Y-11876D01*
X484656D01*
Y-11908D01*
X484591D01*
Y-11941D01*
X484494D01*
Y-11973D01*
X484398D01*
Y-12005D01*
X484333D01*
Y-12037D01*
X484236D01*
Y-12070D01*
X484139D01*
Y-12102D01*
X484043D01*
Y-12134D01*
X483946D01*
Y-12167D01*
X483849D01*
Y-12199D01*
X483752D01*
Y-12231D01*
X483656D01*
Y-12263D01*
X483526D01*
Y-12296D01*
X483430D01*
Y-12328D01*
X483301D01*
Y-12360D01*
X483172D01*
Y-12392D01*
X483042D01*
Y-12425D01*
X482913D01*
Y-12457D01*
X482752D01*
Y-12489D01*
X482623D01*
Y-12521D01*
X482462D01*
Y-12554D01*
X482268D01*
Y-12586D01*
X482075D01*
Y-12618D01*
X481849D01*
Y-12651D01*
X481655D01*
Y-12683D01*
X481268D01*
Y-12715D01*
X480913D01*
Y-12747D01*
X480881D01*
Y-12715D01*
X480816D01*
Y-12747D01*
X479558D01*
Y-12715D01*
X479074D01*
Y-12683D01*
X478784D01*
Y-12651D01*
X478526D01*
Y-12618D01*
X478300D01*
Y-12586D01*
X478106D01*
Y-12554D01*
X477913D01*
Y-12521D01*
X477752D01*
Y-12489D01*
X477590D01*
Y-12457D01*
X477461D01*
Y-12425D01*
X477332D01*
Y-12392D01*
X477203D01*
Y-12360D01*
X477074D01*
Y-12328D01*
X476945D01*
Y-12296D01*
X476848D01*
Y-12263D01*
X476719D01*
Y-12231D01*
X476622D01*
Y-12199D01*
X476526D01*
Y-12167D01*
X476429D01*
Y-12134D01*
X476332D01*
Y-12102D01*
X476235D01*
Y-12070D01*
X476138D01*
Y-12037D01*
X476042D01*
Y-12005D01*
X475945D01*
Y-11973D01*
X475880D01*
Y-11941D01*
X475784D01*
Y-11908D01*
X475719D01*
Y-11876D01*
X475622D01*
Y-11844D01*
X475558D01*
Y-11812D01*
X475461D01*
Y-11779D01*
X475396D01*
Y-11747D01*
X475332D01*
Y-11715D01*
X475267D01*
Y-11683D01*
X475171D01*
Y-11650D01*
X475106D01*
Y-11618D01*
X475042D01*
Y-11586D01*
X474977D01*
Y-11554D01*
X474913D01*
Y-11521D01*
X474848D01*
Y-11489D01*
X474784D01*
Y-11457D01*
X474719D01*
Y-11425D01*
X474654D01*
Y-11392D01*
X474590D01*
Y-11360D01*
X474525D01*
Y-11328D01*
X474461D01*
Y-11295D01*
X474396D01*
Y-11263D01*
X474364D01*
Y-11231D01*
X474299D01*
Y-11199D01*
X474235D01*
Y-11167D01*
X474170D01*
Y-11134D01*
X474106D01*
Y-11102D01*
X474074D01*
Y-11070D01*
X474009D01*
Y-11037D01*
X473945D01*
Y-11005D01*
X473912D01*
Y-10973D01*
X473848D01*
Y-10941D01*
X473816D01*
Y-10908D01*
X473751D01*
Y-10876D01*
X473687D01*
Y-10844D01*
X473654D01*
Y-10812D01*
X473590D01*
Y-10779D01*
X473558D01*
Y-10747D01*
X473493D01*
Y-10715D01*
X473461D01*
Y-10683D01*
X473396D01*
Y-10650D01*
X473364D01*
Y-10618D01*
X473299D01*
Y-10586D01*
X473267D01*
Y-10554D01*
X473203D01*
Y-10521D01*
X473170D01*
Y-10489D01*
X473138D01*
Y-10457D01*
X473074D01*
Y-10424D01*
X473041D01*
Y-10392D01*
X473009D01*
Y-10360D01*
X472944D01*
Y-10328D01*
X472912D01*
Y-10295D01*
X472880D01*
Y-10263D01*
X472816D01*
Y-10231D01*
X472783D01*
Y-10199D01*
X472751D01*
Y-10166D01*
X472686D01*
Y-10134D01*
X472654D01*
Y-10102D01*
X472622D01*
Y-10069D01*
X472590D01*
Y-10037D01*
X472525D01*
Y-10005D01*
X472493D01*
Y-9973D01*
X472461D01*
Y-9940D01*
X472428D01*
Y-9908D01*
X472396D01*
Y-9876D01*
X472332D01*
Y-9844D01*
X472299D01*
Y-9811D01*
X472267D01*
Y-9779D01*
X472235D01*
Y-9747D01*
X472202D01*
Y-9715D01*
X472170D01*
Y-9682D01*
X472138D01*
Y-9650D01*
X472074D01*
Y-9618D01*
X472041D01*
Y-9586D01*
X472009D01*
Y-9553D01*
X471977D01*
Y-9521D01*
X471944D01*
Y-9489D01*
X471912D01*
Y-9457D01*
X471880D01*
Y-9424D01*
X471848D01*
Y-9392D01*
X471815D01*
Y-9360D01*
X471783D01*
Y-9328D01*
X471751D01*
Y-9295D01*
X471719D01*
Y-9263D01*
X471686D01*
Y-9231D01*
X471654D01*
Y-9199D01*
X471622D01*
Y-9166D01*
X471590D01*
Y-9134D01*
X471557D01*
Y-9102D01*
X471525D01*
Y-9069D01*
X471493D01*
Y-9037D01*
X471460D01*
Y-9005D01*
X471428D01*
Y-8973D01*
X471396D01*
Y-8940D01*
X471364D01*
Y-8908D01*
X471332D01*
Y-8876D01*
X471299D01*
Y-8844D01*
X471267D01*
Y-8811D01*
X471235D01*
Y-8779D01*
X471202D01*
Y-8747D01*
Y-8715D01*
X471170D01*
Y-8682D01*
X471138D01*
Y-8650D01*
X471106D01*
Y-8618D01*
X471073D01*
Y-8585D01*
X471041D01*
Y-8553D01*
X471009D01*
Y-8521D01*
X470977D01*
Y-8489D01*
Y-8456D01*
X470944D01*
Y-8424D01*
X470912D01*
Y-8392D01*
X470880D01*
Y-8360D01*
X470848D01*
Y-8327D01*
X470815D01*
Y-8295D01*
Y-8263D01*
X470783D01*
Y-8231D01*
X470751D01*
Y-8198D01*
X470718D01*
Y-8166D01*
X470686D01*
Y-8134D01*
Y-8102D01*
X470654D01*
Y-8069D01*
X470622D01*
Y-8037D01*
X470589D01*
Y-8005D01*
Y-7972D01*
X470557D01*
Y-7940D01*
X470525D01*
Y-7908D01*
X470493D01*
Y-7876D01*
Y-7843D01*
X470460D01*
Y-7811D01*
X470428D01*
Y-7779D01*
X470396D01*
Y-7747D01*
Y-7714D01*
X470364D01*
Y-7682D01*
X470331D01*
Y-7650D01*
X470299D01*
Y-7618D01*
Y-7585D01*
X470267D01*
Y-7553D01*
X470235D01*
Y-7521D01*
Y-7489D01*
X470202D01*
Y-7456D01*
X470170D01*
Y-7424D01*
Y-7392D01*
X470138D01*
Y-7360D01*
X470106D01*
Y-7327D01*
Y-7295D01*
X470073D01*
Y-7263D01*
X470041D01*
Y-7231D01*
Y-7198D01*
X470009D01*
Y-7166D01*
X469977D01*
Y-7134D01*
Y-7102D01*
X469944D01*
Y-7069D01*
Y-7037D01*
X469912D01*
Y-7005D01*
X469880D01*
Y-6972D01*
Y-6940D01*
X469847D01*
Y-6908D01*
X469815D01*
Y-6876D01*
Y-6843D01*
X469783D01*
Y-6811D01*
Y-6779D01*
X469751D01*
Y-6747D01*
Y-6714D01*
X469718D01*
Y-6682D01*
X469686D01*
Y-6650D01*
Y-6617D01*
X469654D01*
Y-6585D01*
Y-6553D01*
X469622D01*
Y-6521D01*
Y-6488D01*
X469589D01*
Y-6456D01*
X469557D01*
Y-6424D01*
Y-6392D01*
X469525D01*
Y-6359D01*
Y-6327D01*
X469492D01*
Y-6295D01*
Y-6263D01*
X469460D01*
Y-6230D01*
Y-6198D01*
X469428D01*
Y-6166D01*
Y-6134D01*
X469396D01*
Y-6101D01*
Y-6069D01*
X469363D01*
Y-6037D01*
Y-6005D01*
X469331D01*
Y-5972D01*
Y-5940D01*
X469299D01*
Y-5908D01*
Y-5875D01*
X469267D01*
Y-5843D01*
Y-5811D01*
X469235D01*
Y-5779D01*
Y-5746D01*
X469202D01*
Y-5714D01*
Y-5682D01*
X469170D01*
Y-5650D01*
Y-5617D01*
Y-5585D01*
X469138D01*
Y-5553D01*
Y-5521D01*
X469105D01*
Y-5488D01*
Y-5456D01*
X469073D01*
Y-5424D01*
Y-5392D01*
Y-5359D01*
X469041D01*
Y-5327D01*
Y-5295D01*
X469009D01*
Y-5263D01*
Y-5230D01*
X468976D01*
Y-5198D01*
Y-5166D01*
Y-5133D01*
X468944D01*
Y-5101D01*
Y-5069D01*
X468912D01*
Y-5037D01*
Y-5004D01*
Y-4972D01*
X468880D01*
Y-4940D01*
Y-4908D01*
Y-4875D01*
X468847D01*
Y-4843D01*
Y-4811D01*
X468815D01*
Y-4779D01*
Y-4746D01*
Y-4714D01*
X468783D01*
Y-4682D01*
Y-4650D01*
Y-4617D01*
X468750D01*
Y-4585D01*
Y-4553D01*
Y-4521D01*
X468718D01*
Y-4488D01*
Y-4456D01*
Y-4424D01*
X468686D01*
Y-4391D01*
Y-4359D01*
Y-4327D01*
X468654D01*
Y-4295D01*
Y-4262D01*
Y-4230D01*
X468621D01*
Y-4198D01*
Y-4166D01*
Y-4133D01*
X468589D01*
Y-4101D01*
Y-4069D01*
Y-4037D01*
Y-4004D01*
X468557D01*
Y-3972D01*
Y-3940D01*
Y-3907D01*
X468525D01*
Y-3875D01*
Y-3843D01*
Y-3811D01*
Y-3779D01*
X468492D01*
Y-3746D01*
Y-3714D01*
Y-3682D01*
Y-3650D01*
X468460D01*
Y-3617D01*
Y-3585D01*
Y-3553D01*
Y-3520D01*
X468428D01*
Y-3488D01*
Y-3456D01*
Y-3424D01*
Y-3391D01*
X468396D01*
Y-3359D01*
Y-3327D01*
Y-3295D01*
Y-3262D01*
Y-3230D01*
X468363D01*
Y-3198D01*
Y-3165D01*
Y-3133D01*
Y-3101D01*
Y-3069D01*
X468331D01*
Y-3036D01*
Y-3004D01*
Y-2972D01*
Y-2940D01*
Y-2907D01*
X468299D01*
Y-2875D01*
Y-2843D01*
Y-2811D01*
Y-2778D01*
Y-2746D01*
X468267D01*
Y-2714D01*
Y-2682D01*
Y-2649D01*
Y-2617D01*
Y-2585D01*
Y-2553D01*
X468234D01*
Y-2520D01*
Y-2488D01*
Y-2456D01*
Y-2424D01*
Y-2391D01*
Y-2359D01*
Y-2327D01*
X468202D01*
Y-2294D01*
Y-2262D01*
Y-2230D01*
Y-2198D01*
Y-2165D01*
Y-2133D01*
Y-2101D01*
Y-2069D01*
X468170D01*
Y-2036D01*
Y-2004D01*
Y-1972D01*
Y-1940D01*
Y-1907D01*
Y-1875D01*
Y-1843D01*
Y-1811D01*
Y-1778D01*
Y-1746D01*
X468138D01*
Y-1714D01*
Y-1681D01*
Y-1649D01*
Y-1617D01*
Y-1585D01*
Y-1552D01*
Y-1520D01*
Y-1488D01*
Y-1456D01*
Y-1423D01*
Y-1391D01*
Y-1359D01*
Y-1327D01*
Y-1294D01*
Y-1262D01*
Y-1230D01*
X468105D01*
Y-1198D01*
Y-1165D01*
Y-1133D01*
Y-1101D01*
Y-1068D01*
Y-1036D01*
D02*
G37*
%LPD*%
G36*
X494754Y-2746D02*
X494818D01*
Y-2778D01*
Y-2811D01*
Y-2843D01*
Y-2875D01*
Y-2907D01*
Y-2940D01*
Y-2972D01*
Y-3004D01*
Y-3036D01*
Y-3069D01*
Y-3101D01*
Y-3133D01*
Y-3165D01*
Y-3198D01*
Y-3230D01*
Y-3262D01*
Y-3295D01*
Y-3327D01*
Y-3359D01*
Y-3391D01*
Y-3424D01*
Y-3456D01*
Y-3488D01*
Y-3520D01*
Y-3553D01*
Y-3585D01*
Y-3617D01*
Y-3650D01*
Y-3682D01*
Y-3714D01*
Y-3746D01*
Y-3779D01*
Y-3811D01*
Y-3843D01*
Y-3875D01*
Y-3907D01*
Y-3940D01*
Y-3972D01*
Y-4004D01*
Y-4037D01*
Y-4069D01*
Y-4101D01*
Y-4133D01*
Y-4166D01*
Y-4198D01*
Y-4230D01*
Y-4262D01*
Y-4295D01*
Y-4327D01*
Y-4359D01*
Y-4391D01*
Y-4424D01*
Y-4456D01*
Y-4488D01*
Y-4521D01*
Y-4553D01*
Y-4585D01*
Y-4617D01*
Y-4650D01*
Y-4682D01*
Y-4714D01*
Y-4746D01*
Y-4779D01*
Y-4811D01*
Y-4843D01*
Y-4875D01*
Y-4908D01*
Y-4940D01*
Y-4972D01*
Y-5004D01*
Y-5037D01*
Y-5069D01*
Y-5101D01*
Y-5133D01*
Y-5166D01*
Y-5198D01*
Y-5230D01*
Y-5263D01*
Y-5295D01*
Y-5327D01*
Y-5359D01*
Y-5392D01*
Y-5424D01*
Y-5456D01*
Y-5488D01*
Y-5521D01*
Y-5553D01*
Y-5585D01*
Y-5617D01*
Y-5650D01*
Y-5682D01*
Y-5714D01*
Y-5746D01*
Y-5779D01*
Y-5811D01*
Y-5843D01*
Y-5875D01*
Y-5908D01*
Y-5940D01*
Y-5972D01*
Y-6005D01*
Y-6037D01*
Y-6069D01*
Y-6101D01*
Y-6134D01*
Y-6166D01*
Y-6198D01*
Y-6230D01*
Y-6263D01*
Y-6295D01*
Y-6327D01*
X492463D01*
Y-6295D01*
Y-6263D01*
Y-6230D01*
Y-6198D01*
Y-6166D01*
Y-6134D01*
Y-6101D01*
Y-6069D01*
Y-6037D01*
Y-6005D01*
Y-5972D01*
Y-5940D01*
Y-5908D01*
Y-5875D01*
Y-5843D01*
Y-5811D01*
Y-5779D01*
Y-5746D01*
Y-5714D01*
Y-5682D01*
Y-5650D01*
Y-5617D01*
Y-5585D01*
Y-5553D01*
Y-5521D01*
Y-5488D01*
Y-5456D01*
Y-5424D01*
Y-5392D01*
Y-5359D01*
Y-5327D01*
Y-5295D01*
Y-5263D01*
Y-5230D01*
Y-5198D01*
Y-5166D01*
Y-5133D01*
Y-5101D01*
Y-5069D01*
Y-5037D01*
Y-5004D01*
Y-4972D01*
Y-4940D01*
Y-4908D01*
Y-4875D01*
Y-4843D01*
Y-4811D01*
Y-4779D01*
Y-4746D01*
Y-4714D01*
Y-4682D01*
Y-4650D01*
Y-4617D01*
Y-4585D01*
Y-4553D01*
Y-4521D01*
Y-4488D01*
Y-4456D01*
Y-4424D01*
Y-4391D01*
Y-4359D01*
Y-4327D01*
Y-4295D01*
Y-4262D01*
Y-4230D01*
Y-4198D01*
Y-4166D01*
Y-4133D01*
Y-4101D01*
Y-4069D01*
Y-4037D01*
Y-4004D01*
Y-3972D01*
Y-3940D01*
Y-3907D01*
Y-3875D01*
Y-3843D01*
Y-3811D01*
Y-3779D01*
Y-3746D01*
Y-3714D01*
Y-3682D01*
Y-3650D01*
Y-3617D01*
Y-3585D01*
Y-3553D01*
Y-3520D01*
Y-3488D01*
Y-3456D01*
Y-3424D01*
Y-3391D01*
Y-3359D01*
Y-3327D01*
Y-3295D01*
Y-3262D01*
Y-3230D01*
Y-3198D01*
Y-3165D01*
Y-3133D01*
Y-3101D01*
Y-3069D01*
Y-3036D01*
Y-3004D01*
Y-2972D01*
Y-2940D01*
Y-2907D01*
Y-2875D01*
Y-2843D01*
Y-2811D01*
Y-2778D01*
Y-2746D01*
X492495D01*
Y-2714D01*
X492527D01*
Y-2746D01*
X494625D01*
Y-2714D01*
X494657D01*
Y-2746D01*
X494721D01*
Y-2714D01*
X494754D01*
Y-2746D01*
D02*
G37*
G36*
X487946Y-2682D02*
Y-2714D01*
Y-2746D01*
Y-2778D01*
Y-2811D01*
Y-2843D01*
Y-2875D01*
Y-2907D01*
Y-2940D01*
Y-2972D01*
Y-3004D01*
Y-3036D01*
Y-3069D01*
Y-3101D01*
Y-3133D01*
Y-3165D01*
Y-3198D01*
Y-3230D01*
Y-3262D01*
Y-3295D01*
Y-3327D01*
Y-3359D01*
Y-3391D01*
Y-3424D01*
Y-3456D01*
Y-3488D01*
Y-3520D01*
Y-3553D01*
Y-3585D01*
Y-3617D01*
Y-3650D01*
Y-3682D01*
Y-3714D01*
Y-3746D01*
Y-3779D01*
Y-3811D01*
Y-3843D01*
Y-3875D01*
Y-3907D01*
Y-3940D01*
Y-3972D01*
Y-4004D01*
Y-4037D01*
Y-4069D01*
Y-4101D01*
Y-4133D01*
Y-4166D01*
Y-4198D01*
Y-4230D01*
Y-4262D01*
Y-4295D01*
Y-4327D01*
Y-4359D01*
X485527D01*
Y-4327D01*
Y-4295D01*
Y-4262D01*
Y-4230D01*
Y-4198D01*
Y-4166D01*
Y-4133D01*
Y-4101D01*
Y-4069D01*
Y-4037D01*
Y-4004D01*
Y-3972D01*
Y-3940D01*
Y-3907D01*
Y-3875D01*
Y-3843D01*
Y-3811D01*
Y-3779D01*
Y-3746D01*
Y-3714D01*
Y-3682D01*
Y-3650D01*
Y-3617D01*
Y-3585D01*
Y-3553D01*
Y-3520D01*
Y-3488D01*
Y-3456D01*
Y-3424D01*
Y-3391D01*
Y-3359D01*
Y-3327D01*
Y-3295D01*
Y-3262D01*
Y-3230D01*
Y-3198D01*
Y-3165D01*
Y-3133D01*
Y-3101D01*
Y-3069D01*
Y-3036D01*
Y-3004D01*
Y-2972D01*
Y-2940D01*
Y-2907D01*
Y-2875D01*
Y-2843D01*
Y-2811D01*
Y-2778D01*
Y-2746D01*
Y-2714D01*
Y-2682D01*
Y-2649D01*
X487946D01*
Y-2682D01*
D02*
G37*
%LPC*%
G36*
X580623Y13658D02*
X575909D01*
Y8945D01*
X580623D01*
Y13658D01*
D02*
G37*
G36*
X572909D02*
X568196D01*
Y8945D01*
X572909D01*
Y13658D01*
D02*
G37*
G36*
X580623Y5945D02*
X575909D01*
Y1232D01*
X580623D01*
Y5945D01*
D02*
G37*
G36*
X572909D02*
X568196D01*
Y1232D01*
X572909D01*
Y5945D01*
D02*
G37*
G36*
X575909Y-3018D02*
Y-7555D01*
X580446D01*
X580384Y-7243D01*
X579916Y-6112D01*
X579236Y-5094D01*
X578370Y-4229D01*
X577353Y-3549D01*
X576222Y-3080D01*
X575909Y-3018D01*
D02*
G37*
G36*
X572909Y-3018D02*
X572597Y-3080D01*
X571466Y-3549D01*
X570449Y-4229D01*
X569583Y-5094D01*
X568903Y-6112D01*
X568435Y-7243D01*
X568373Y-7555D01*
X572909D01*
Y-3018D01*
D02*
G37*
G36*
Y-10555D02*
X568373D01*
X568435Y-10868D01*
X568903Y-11998D01*
X569583Y-13016D01*
X570449Y-13881D01*
X571466Y-14561D01*
X572597Y-15030D01*
X572909Y-15092D01*
Y-10555D01*
D02*
G37*
G36*
X580446D02*
X575909D01*
Y-15092D01*
X576222Y-15030D01*
X577353Y-14561D01*
X578370Y-13881D01*
X579236Y-13016D01*
X579916Y-11998D01*
X580384Y-10868D01*
X580446Y-10555D01*
D02*
G37*
G36*
X554209Y13482D02*
Y8945D01*
X558746D01*
X558684Y9257D01*
X558216Y10388D01*
X557536Y11406D01*
X556670Y12271D01*
X555653Y12951D01*
X554522Y13419D01*
X554209Y13482D01*
D02*
G37*
G36*
X551209Y13482D02*
X550897Y13419D01*
X549766Y12951D01*
X548749Y12271D01*
X547883Y11406D01*
X547203Y10388D01*
X546735Y9257D01*
X546673Y8945D01*
X551209D01*
Y13482D01*
D02*
G37*
G36*
Y5945D02*
X546673D01*
X546735Y5632D01*
X547203Y4502D01*
X547883Y3484D01*
X548749Y2619D01*
X549766Y1939D01*
X550897Y1470D01*
X551209Y1408D01*
Y5945D01*
D02*
G37*
G36*
X558746D02*
X554209D01*
Y1408D01*
X554522Y1470D01*
X555653Y1939D01*
X556670Y2619D01*
X557536Y3484D01*
X558216Y4502D01*
X558684Y5632D01*
X558746Y5945D01*
D02*
G37*
G36*
X554209Y-3018D02*
Y-7555D01*
X558746D01*
X558684Y-7243D01*
X558216Y-6112D01*
X557536Y-5094D01*
X556670Y-4229D01*
X555653Y-3549D01*
X554522Y-3080D01*
X554209Y-3018D01*
D02*
G37*
G36*
X551209Y-3018D02*
X550897Y-3080D01*
X549766Y-3549D01*
X548749Y-4229D01*
X547883Y-5094D01*
X547203Y-6112D01*
X546735Y-7243D01*
X546673Y-7555D01*
X551209D01*
Y-3018D01*
D02*
G37*
G36*
Y-10555D02*
X546673D01*
X546735Y-10868D01*
X547203Y-11998D01*
X547883Y-13016D01*
X548749Y-13881D01*
X549766Y-14561D01*
X550897Y-15030D01*
X551209Y-15092D01*
Y-10555D01*
D02*
G37*
G36*
X558746D02*
X554209D01*
Y-15092D01*
X554522Y-15030D01*
X555653Y-14561D01*
X556670Y-13881D01*
X557536Y-13016D01*
X558216Y-11998D01*
X558684Y-10868D01*
X558746Y-10555D01*
D02*
G37*
G36*
X543948Y-24964D02*
X539748D01*
Y-26114D01*
X543948D01*
Y-24964D01*
D02*
G37*
G36*
Y-29114D02*
X539748D01*
Y-30264D01*
X543948D01*
Y-29114D01*
D02*
G37*
G36*
X118468Y-34420D02*
X117752D01*
X117091Y-34694D01*
X116584Y-35201D01*
X116310Y-35862D01*
Y-36579D01*
X116584Y-37240D01*
X117091Y-37746D01*
X117752Y-38021D01*
X118468D01*
X119130Y-37746D01*
X119636Y-37240D01*
X119910Y-36579D01*
Y-35862D01*
X119636Y-35201D01*
X119130Y-34694D01*
X118468Y-34420D01*
D02*
G37*
G36*
X209807Y8887D02*
X209091D01*
X208429Y8613D01*
X207923Y8106D01*
X207649Y7445D01*
Y6729D01*
X207923Y6067D01*
X208429Y5561D01*
X209091Y5287D01*
X209807D01*
X210468Y5561D01*
X210975Y6067D01*
X211249Y6729D01*
Y7445D01*
X210975Y8106D01*
X210468Y8613D01*
X209807Y8887D01*
D02*
G37*
G36*
X214531Y2981D02*
X213815D01*
X213154Y2707D01*
X212647Y2201D01*
X212373Y1539D01*
Y823D01*
X212647Y161D01*
X213154Y-345D01*
X213815Y-619D01*
X214531D01*
X215193Y-345D01*
X215699Y161D01*
X215973Y823D01*
Y1539D01*
X215699Y2201D01*
X215193Y2707D01*
X214531Y2981D01*
D02*
G37*
G36*
X51645Y-125078D02*
X50929D01*
X50267Y-125352D01*
X49761Y-125858D01*
X49487Y-126520D01*
Y-127236D01*
X49761Y-127897D01*
X50267Y-128404D01*
X50929Y-128678D01*
X51645D01*
X52307Y-128404D01*
X52813Y-127897D01*
X53087Y-127236D01*
Y-126520D01*
X52813Y-125858D01*
X52307Y-125352D01*
X51645Y-125078D01*
D02*
G37*
G36*
X13744D02*
X13028D01*
X12366Y-125352D01*
X11860Y-125858D01*
X11586Y-126520D01*
Y-127236D01*
X11860Y-127897D01*
X12366Y-128404D01*
X13028Y-128678D01*
X13744D01*
X14405Y-128404D01*
X14912Y-127897D01*
X15186Y-127236D01*
Y-126520D01*
X14912Y-125858D01*
X14405Y-125352D01*
X13744Y-125078D01*
D02*
G37*
G36*
X22728Y-145503D02*
X22209Y-145718D01*
X21980Y-145947D01*
X21654Y-146188D01*
X21327Y-145947D01*
X21098Y-145718D01*
X20579Y-145503D01*
Y-147244D01*
X19579D01*
Y-145503D01*
X19059Y-145718D01*
X18701Y-146077D01*
X18342Y-145718D01*
X17823Y-145503D01*
Y-147244D01*
X17323D01*
Y-147744D01*
X15582D01*
X15670Y-147958D01*
X15338Y-148458D01*
X14646D01*
Y-151025D01*
X19976D01*
X25307D01*
Y-148458D01*
X25213D01*
X24881Y-147958D01*
X24970Y-147744D01*
X23228D01*
Y-147244D01*
X22728D01*
Y-145503D01*
D02*
G37*
G36*
X23728D02*
Y-146744D01*
X24970D01*
X24754Y-146224D01*
X24248Y-145718D01*
X23728Y-145503D01*
D02*
G37*
G36*
X16823D02*
X16303Y-145718D01*
X15797Y-146224D01*
X15582Y-146744D01*
X16823D01*
Y-145503D01*
D02*
G37*
G36*
X2237Y-142002D02*
X2035D01*
Y-146832D01*
X6866D01*
Y-146631D01*
X6503Y-145275D01*
X5801Y-144059D01*
X4809Y-143067D01*
X3593Y-142365D01*
X2237Y-142002D01*
D02*
G37*
G36*
X-17763D02*
X-17965D01*
Y-146832D01*
X-13134D01*
Y-146631D01*
X-13497Y-145275D01*
X-14199Y-144059D01*
X-15191Y-143067D01*
X-16407Y-142365D01*
X-17763Y-142002D01*
D02*
G37*
G36*
X1035D02*
X834D01*
X-522Y-142365D01*
X-1738Y-143067D01*
X-2730Y-144059D01*
X-3432Y-145275D01*
X-3795Y-146631D01*
Y-146832D01*
X1035D01*
Y-142002D01*
D02*
G37*
G36*
X-18965D02*
X-19166D01*
X-20522Y-142365D01*
X-21738Y-143067D01*
X-22730Y-144059D01*
X-23432Y-145275D01*
X-23795Y-146631D01*
Y-146832D01*
X-18965D01*
Y-142002D01*
D02*
G37*
G36*
X6866Y-147832D02*
X2035D01*
Y-152663D01*
X2237D01*
X3593Y-152300D01*
X4809Y-151598D01*
X5801Y-150605D01*
X6503Y-149390D01*
X6866Y-148034D01*
Y-147832D01*
D02*
G37*
G36*
X1035D02*
X-3795D01*
Y-148034D01*
X-3432Y-149390D01*
X-2730Y-150605D01*
X-1738Y-151598D01*
X-522Y-152300D01*
X834Y-152663D01*
X1035D01*
Y-147832D01*
D02*
G37*
G36*
X-13134D02*
X-17965D01*
Y-152663D01*
X-17763D01*
X-16407Y-152300D01*
X-15191Y-151598D01*
X-14199Y-150605D01*
X-13497Y-149390D01*
X-13134Y-148034D01*
Y-147832D01*
D02*
G37*
G36*
X-18965D02*
X-23795D01*
Y-148034D01*
X-23432Y-149390D01*
X-22730Y-150605D01*
X-21738Y-151598D01*
X-20522Y-152300D01*
X-19166Y-152663D01*
X-18965D01*
Y-147832D01*
D02*
G37*
G36*
X25307Y-152025D02*
X20477D01*
Y-154592D01*
X25307D01*
Y-152025D01*
D02*
G37*
G36*
X19477D02*
X14646D01*
Y-154364D01*
X10906D01*
Y-155905D01*
X-3528D01*
Y-152395D01*
X-13402D01*
Y-162269D01*
X-3528D01*
Y-158760D01*
X10906D01*
Y-160301D01*
X12545D01*
Y-161565D01*
X10236D01*
X9690Y-161673D01*
X9227Y-161983D01*
X8918Y-162446D01*
X8809Y-162992D01*
Y-172819D01*
X7858D01*
Y-174163D01*
X7480D01*
X6934Y-174272D01*
X6471Y-174581D01*
X6224Y-174950D01*
X5752Y-174878D01*
X5724Y-174867D01*
Y-174787D01*
X-213D01*
Y-182299D01*
X5724D01*
Y-179971D01*
X7480D01*
X8027Y-179862D01*
X8490Y-179553D01*
X8799Y-179090D01*
X8888Y-178640D01*
X9159Y-178530D01*
X9323Y-178521D01*
X9639Y-178917D01*
X9596Y-179134D01*
Y-183268D01*
X9613Y-183351D01*
X9296Y-183917D01*
X8841Y-184222D01*
X8823Y-184229D01*
X8317Y-184736D01*
X8043Y-185397D01*
Y-186113D01*
X8317Y-186775D01*
X8823Y-187281D01*
X9484Y-187555D01*
X10201D01*
X10862Y-187281D01*
X11368Y-186775D01*
X11415Y-186664D01*
X11992D01*
Y-188795D01*
X12283D01*
X12490Y-189295D01*
X12254Y-189532D01*
X11980Y-190193D01*
Y-190909D01*
X11719Y-191299D01*
X10872D01*
Y-193307D01*
Y-195315D01*
X15394D01*
Y-191357D01*
X15579Y-190909D01*
Y-190506D01*
X15794Y-190186D01*
X15902Y-189639D01*
X15902Y-189639D01*
Y-188795D01*
X17339D01*
Y-186827D01*
Y-182890D01*
Y-179709D01*
X17339D01*
X17161Y-179209D01*
X17176Y-179134D01*
Y-178362D01*
X18126D01*
Y-172819D01*
X13370D01*
Y-177706D01*
X12614D01*
Y-172819D01*
X11664D01*
Y-164420D01*
X13973D01*
X14146Y-164385D01*
X14646Y-164782D01*
Y-166206D01*
X14902D01*
X15236Y-166706D01*
X15188Y-166823D01*
X16929D01*
Y-167323D01*
X17429D01*
Y-169064D01*
X17949Y-168849D01*
X18307Y-168491D01*
X18665Y-168849D01*
X19185Y-169064D01*
Y-167323D01*
X20185D01*
Y-169064D01*
X20705Y-168849D01*
X21063Y-168491D01*
X21421Y-168849D01*
X21941Y-169064D01*
Y-167323D01*
X22441D01*
Y-166823D01*
X24182D01*
X24134Y-166706D01*
X24468Y-166206D01*
X25307D01*
Y-163639D01*
X19976D01*
Y-163139D01*
X19477D01*
Y-160072D01*
X17040D01*
Y-154592D01*
X19477D01*
Y-152025D01*
D02*
G37*
G36*
X25307Y-160072D02*
X20477D01*
Y-162639D01*
X25307D01*
Y-160072D01*
D02*
G37*
G36*
X2237Y-162002D02*
X2035D01*
Y-166832D01*
X6866D01*
Y-166630D01*
X6503Y-165275D01*
X5801Y-164059D01*
X4809Y-163067D01*
X3593Y-162365D01*
X2237Y-162002D01*
D02*
G37*
G36*
X-17763D02*
X-17965D01*
Y-166832D01*
X-13134D01*
Y-166630D01*
X-13497Y-165275D01*
X-14199Y-164059D01*
X-15191Y-163067D01*
X-16407Y-162365D01*
X-17763Y-162002D01*
D02*
G37*
G36*
X1035D02*
X834D01*
X-522Y-162365D01*
X-1738Y-163067D01*
X-2730Y-164059D01*
X-3432Y-165275D01*
X-3795Y-166630D01*
Y-166832D01*
X1035D01*
Y-162002D01*
D02*
G37*
G36*
X-18965D02*
X-19166D01*
X-20522Y-162365D01*
X-21738Y-163067D01*
X-22730Y-164059D01*
X-23432Y-165275D01*
X-23795Y-166630D01*
Y-166832D01*
X-18965D01*
Y-162002D01*
D02*
G37*
G36*
X24182Y-167823D02*
X22941D01*
Y-169064D01*
X23461Y-168849D01*
X23967Y-168342D01*
X24182Y-167823D01*
D02*
G37*
G36*
X16429D02*
X15188D01*
X15403Y-168342D01*
X15910Y-168849D01*
X16429Y-169064D01*
Y-167823D01*
D02*
G37*
G36*
X6866Y-167832D02*
X2035D01*
Y-172663D01*
X2237D01*
X3593Y-172300D01*
X4809Y-171598D01*
X5801Y-170605D01*
X6503Y-169390D01*
X6866Y-168034D01*
Y-167832D01*
D02*
G37*
G36*
X1035D02*
X-3795D01*
Y-168034D01*
X-3432Y-169390D01*
X-2730Y-170605D01*
X-1738Y-171598D01*
X-522Y-172300D01*
X834Y-172663D01*
X1035D01*
Y-167832D01*
D02*
G37*
G36*
X-13134D02*
X-17965D01*
Y-172663D01*
X-17763D01*
X-16407Y-172300D01*
X-15191Y-171598D01*
X-14199Y-170605D01*
X-13497Y-169390D01*
X-13134Y-168034D01*
Y-167832D01*
D02*
G37*
G36*
X-18965D02*
X-23795D01*
Y-168034D01*
X-23432Y-169390D01*
X-22730Y-170605D01*
X-21738Y-171598D01*
X-20522Y-172300D01*
X-19166Y-172663D01*
X-18965D01*
Y-167832D01*
D02*
G37*
G36*
X-15634Y-174591D02*
X-21177D01*
Y-175585D01*
X-22734D01*
X-23264Y-175365D01*
X-23980D01*
X-24642Y-175639D01*
X-25148Y-176146D01*
X-25422Y-176807D01*
Y-177523D01*
X-25148Y-178185D01*
X-24642Y-178691D01*
X-24227Y-178863D01*
Y-179404D01*
X-24642Y-179576D01*
X-25148Y-180083D01*
X-25422Y-180744D01*
Y-181460D01*
X-25148Y-182122D01*
X-24691Y-182579D01*
X-25148Y-183036D01*
X-25422Y-183697D01*
Y-184413D01*
X-25148Y-185075D01*
X-24642Y-185581D01*
X-24227Y-185753D01*
Y-186294D01*
X-24642Y-186466D01*
X-25148Y-186972D01*
X-25422Y-187634D01*
Y-188350D01*
X-25148Y-189012D01*
X-24642Y-189518D01*
X-23980Y-189792D01*
X-23264D01*
X-22602Y-189518D01*
X-22507Y-189423D01*
X-21177D01*
Y-189976D01*
X-15634D01*
Y-185614D01*
X-17602D01*
Y-182693D01*
Y-178953D01*
X-15634D01*
Y-174591D01*
D02*
G37*
G36*
X-1756Y-174787D02*
X-7693D01*
Y-177014D01*
X-9417D01*
X-9610Y-176821D01*
X-10272Y-176547D01*
X-10988D01*
X-11649Y-176821D01*
X-12156Y-177327D01*
X-12430Y-177988D01*
Y-178705D01*
X-12156Y-179366D01*
X-11649Y-179872D01*
X-10988Y-180147D01*
X-10272D01*
X-10094Y-180073D01*
X-7693D01*
Y-182299D01*
X-1756D01*
Y-174787D01*
D02*
G37*
G36*
X27665Y-177393D02*
Y-178634D01*
X28907D01*
X28691Y-178114D01*
X28185Y-177608D01*
X27665Y-177393D01*
D02*
G37*
G36*
X26665D02*
X26146Y-177608D01*
X25639Y-178114D01*
X25424Y-178634D01*
X26665D01*
Y-177393D01*
D02*
G37*
G36*
X29060Y-179634D02*
X25271D01*
X25221Y-179709D01*
X24394D01*
Y-180799D01*
X27067D01*
X29740D01*
Y-179709D01*
X29110D01*
X29060Y-179634D01*
D02*
G37*
G36*
X-8374Y-189476D02*
X-9615D01*
X-9400Y-189996D01*
X-8894Y-190502D01*
X-8374Y-190718D01*
Y-189476D01*
D02*
G37*
G36*
X-4437Y-183449D02*
X-7693D01*
Y-187176D01*
X-8232D01*
X-8894Y-187450D01*
X-9400Y-187957D01*
X-9615Y-188476D01*
X-7874D01*
Y-188976D01*
X-7374D01*
Y-190961D01*
X-4437D01*
Y-187205D01*
Y-183449D01*
D02*
G37*
G36*
X9872Y-191299D02*
X8228D01*
Y-192807D01*
X9872D01*
Y-191299D01*
D02*
G37*
G36*
X5724Y-183449D02*
X-3437D01*
Y-187205D01*
Y-190961D01*
X2571D01*
Y-192200D01*
X2571Y-192200D01*
X2680Y-192746D01*
X2989Y-193209D01*
X6044Y-196263D01*
Y-196742D01*
X5544Y-196950D01*
X4809Y-196215D01*
X3593Y-195513D01*
X2237Y-195150D01*
X2035D01*
Y-200480D01*
Y-205811D01*
X2237D01*
X3593Y-205448D01*
X4809Y-204746D01*
X5801Y-203753D01*
X6503Y-202538D01*
X6866Y-201182D01*
Y-200872D01*
X7328Y-200681D01*
X12545Y-205898D01*
Y-207661D01*
X10906D01*
Y-209203D01*
X-3528D01*
Y-205543D01*
X-13402D01*
Y-215417D01*
X-3528D01*
Y-212057D01*
X10906D01*
Y-213598D01*
X12545D01*
Y-214321D01*
X11417D01*
X10871Y-214429D01*
X10408Y-214739D01*
X10099Y-215202D01*
X9990Y-215748D01*
Y-218094D01*
X8646D01*
Y-222850D01*
X14189D01*
Y-219608D01*
X14646Y-219504D01*
Y-219504D01*
X17979D01*
X18257Y-219920D01*
X18235Y-219972D01*
X21718D01*
X21696Y-219920D01*
X21974Y-219504D01*
X25307D01*
Y-216937D01*
X19976D01*
Y-216437D01*
X19477D01*
Y-213370D01*
X17040D01*
Y-207890D01*
X19477D01*
Y-204823D01*
X19977D01*
Y-204323D01*
X25307D01*
Y-201756D01*
X21974D01*
X21696Y-201340D01*
X21718Y-201287D01*
X18235D01*
X18257Y-201340D01*
X17979Y-201756D01*
X14646D01*
Y-203308D01*
X14184Y-203499D01*
X10622Y-199938D01*
X10830Y-199438D01*
X10988D01*
X11649Y-199164D01*
X12156Y-198657D01*
X12371Y-198138D01*
X10630D01*
Y-197638D01*
X10130D01*
Y-195897D01*
X9610Y-196112D01*
X9420Y-196302D01*
X8979Y-196129D01*
X8919Y-195703D01*
X9249Y-195315D01*
X9872D01*
Y-193807D01*
X8108D01*
X7766Y-193949D01*
X5426Y-191609D01*
Y-190961D01*
X5724D01*
Y-183449D01*
D02*
G37*
G36*
X11130Y-195897D02*
Y-197138D01*
X12371D01*
X12156Y-196618D01*
X11649Y-196112D01*
X11130Y-195897D01*
D02*
G37*
G36*
X-17763Y-195150D02*
X-17965D01*
Y-199980D01*
X-13134D01*
Y-199778D01*
X-13497Y-198423D01*
X-14199Y-197207D01*
X-15191Y-196215D01*
X-16407Y-195513D01*
X-17763Y-195150D01*
D02*
G37*
G36*
X-18965D02*
X-19166D01*
X-20522Y-195513D01*
X-21738Y-196215D01*
X-22730Y-197207D01*
X-23432Y-198423D01*
X-23795Y-199778D01*
Y-199980D01*
X-18965D01*
Y-195150D01*
D02*
G37*
G36*
X1035D02*
X834D01*
X-522Y-195513D01*
X-1738Y-196215D01*
X-2730Y-197207D01*
X-3432Y-198423D01*
X-3795Y-199778D01*
Y-199980D01*
X1035D01*
Y-195150D01*
D02*
G37*
G36*
X20477Y-199046D02*
Y-200287D01*
X21718D01*
X21502Y-199768D01*
X20996Y-199261D01*
X20477Y-199046D01*
D02*
G37*
G36*
X19477D02*
X18957Y-199261D01*
X18451Y-199768D01*
X18235Y-200287D01*
X19477D01*
Y-199046D01*
D02*
G37*
G36*
X1035Y-200980D02*
X-3795D01*
Y-201182D01*
X-3432Y-202538D01*
X-2730Y-203753D01*
X-1738Y-204746D01*
X-522Y-205448D01*
X834Y-205811D01*
X1035D01*
Y-200980D01*
D02*
G37*
G36*
X-13134D02*
X-17965D01*
Y-205811D01*
X-17763D01*
X-16407Y-205448D01*
X-15191Y-204746D01*
X-14199Y-203753D01*
X-13497Y-202538D01*
X-13134Y-201182D01*
Y-200980D01*
D02*
G37*
G36*
X-18965D02*
X-23795D01*
Y-201182D01*
X-23432Y-202538D01*
X-22730Y-203753D01*
X-21738Y-204746D01*
X-20522Y-205448D01*
X-19166Y-205811D01*
X-18965D01*
Y-200980D01*
D02*
G37*
G36*
X25307Y-205323D02*
X20477D01*
Y-207890D01*
X25307D01*
Y-205323D01*
D02*
G37*
G36*
Y-213370D02*
X20477D01*
Y-215937D01*
X25307D01*
Y-213370D01*
D02*
G37*
G36*
X-17763Y-215150D02*
X-17965D01*
Y-219980D01*
X-13134D01*
Y-219778D01*
X-13497Y-218423D01*
X-14199Y-217207D01*
X-15191Y-216215D01*
X-16407Y-215513D01*
X-17763Y-215150D01*
D02*
G37*
G36*
X2237D02*
X2035D01*
Y-219980D01*
X6866D01*
Y-219778D01*
X6503Y-218423D01*
X5801Y-217207D01*
X4809Y-216215D01*
X3593Y-215513D01*
X2237Y-215150D01*
D02*
G37*
G36*
X-18965D02*
X-19166D01*
X-20522Y-215513D01*
X-21738Y-216215D01*
X-22730Y-217207D01*
X-23432Y-218423D01*
X-23795Y-219778D01*
Y-219980D01*
X-18965D01*
Y-215150D01*
D02*
G37*
G36*
X1035D02*
X834D01*
X-522Y-215513D01*
X-1738Y-216215D01*
X-2730Y-217207D01*
X-3432Y-218423D01*
X-3795Y-219778D01*
Y-219980D01*
X1035D01*
Y-215150D01*
D02*
G37*
G36*
X21718Y-220972D02*
X20477D01*
Y-222214D01*
X20996Y-221998D01*
X21502Y-221492D01*
X21718Y-220972D01*
D02*
G37*
G36*
X19477D02*
X18235D01*
X18451Y-221492D01*
X18957Y-221998D01*
X19477Y-222214D01*
Y-220972D01*
D02*
G37*
G36*
X6866Y-220980D02*
X2035D01*
Y-225811D01*
X2237D01*
X3593Y-225448D01*
X4809Y-224746D01*
X5801Y-223753D01*
X6503Y-222538D01*
X6866Y-221182D01*
Y-220980D01*
D02*
G37*
G36*
X1035D02*
X-3795D01*
Y-221182D01*
X-3432Y-222538D01*
X-2730Y-223753D01*
X-1738Y-224746D01*
X-522Y-225448D01*
X834Y-225811D01*
X1035D01*
Y-220980D01*
D02*
G37*
G36*
X-13134D02*
X-17965D01*
Y-225811D01*
X-17763D01*
X-16407Y-225448D01*
X-15191Y-224746D01*
X-14199Y-223753D01*
X-13497Y-222538D01*
X-13134Y-221182D01*
Y-220980D01*
D02*
G37*
G36*
X-18965D02*
X-23795D01*
Y-221182D01*
X-23432Y-222538D01*
X-22730Y-223753D01*
X-21738Y-224746D01*
X-20522Y-225448D01*
X-19166Y-225811D01*
X-18965D01*
Y-220980D01*
D02*
G37*
G36*
X-15634Y-227346D02*
X-21177D01*
Y-228002D01*
X-22406D01*
X-22602Y-227805D01*
X-23264Y-227531D01*
X-23980D01*
X-24642Y-227805D01*
X-25148Y-228311D01*
X-25422Y-228973D01*
Y-229689D01*
X-25148Y-230350D01*
X-24642Y-230857D01*
X-24227Y-231029D01*
Y-231570D01*
X-24642Y-231742D01*
X-25148Y-232248D01*
X-25422Y-232910D01*
Y-233626D01*
X-25148Y-234287D01*
X-24642Y-234794D01*
X-24227Y-234966D01*
Y-235507D01*
X-24642Y-235679D01*
X-25148Y-236185D01*
X-25422Y-236847D01*
Y-237563D01*
X-25148Y-238224D01*
X-24642Y-238731D01*
X-24227Y-238903D01*
Y-239444D01*
X-24642Y-239616D01*
X-25148Y-240122D01*
X-25422Y-240784D01*
Y-241500D01*
X-25148Y-242161D01*
X-24642Y-242668D01*
X-23980Y-242942D01*
X-23264D01*
X-22602Y-242668D01*
X-22491Y-242556D01*
X-21177D01*
Y-242732D01*
X-15634D01*
Y-238370D01*
X-17602D01*
Y-235449D01*
Y-231709D01*
X-15634D01*
Y-227346D01*
D02*
G37*
G36*
X29740Y-227346D02*
X27567D01*
Y-228437D01*
X29740D01*
Y-227346D01*
D02*
G37*
G36*
X26567D02*
X24394D01*
Y-228437D01*
X26567D01*
Y-227346D01*
D02*
G37*
G36*
X34620Y-227196D02*
X34101Y-227411D01*
X33595Y-227917D01*
X33379Y-228437D01*
X34620D01*
Y-227196D01*
D02*
G37*
G36*
X14189Y-223606D02*
X8646D01*
Y-228362D01*
X9990D01*
Y-230906D01*
X10004Y-230975D01*
X9604Y-231527D01*
X9461Y-231555D01*
X8998Y-231865D01*
X8688Y-232328D01*
X8661Y-232465D01*
X1165D01*
Y-232962D01*
X665Y-233176D01*
X646Y-233168D01*
X-70D01*
X-732Y-233442D01*
X-1238Y-233948D01*
X-1512Y-234610D01*
Y-235326D01*
X-1238Y-235987D01*
X-732Y-236494D01*
X-70Y-236768D01*
X646D01*
X912Y-236658D01*
X1165Y-236827D01*
Y-236827D01*
X4590D01*
X4689Y-237327D01*
X4564Y-237379D01*
X4058Y-237885D01*
X3842Y-238405D01*
X5584D01*
Y-238905D01*
X6084D01*
Y-240646D01*
X6603Y-240431D01*
X7109Y-239924D01*
X7160Y-239803D01*
X7903D01*
Y-237795D01*
X8903D01*
Y-239803D01*
X13426D01*
Y-239223D01*
X14665D01*
X14772Y-239202D01*
X15023D01*
X15685Y-238928D01*
X16191Y-238421D01*
X16465Y-237760D01*
Y-237043D01*
X16385Y-236849D01*
X16662Y-236433D01*
X17338D01*
Y-234465D01*
Y-230528D01*
Y-227346D01*
X14189D01*
Y-223606D01*
D02*
G37*
G36*
X5083Y-239405D02*
X3842D01*
X4058Y-239924D01*
X4564Y-240431D01*
X5083Y-240646D01*
Y-239405D01*
D02*
G37*
G36*
X20477Y-251212D02*
Y-252453D01*
X21718D01*
X21502Y-251933D01*
X20996Y-251427D01*
X20477Y-251212D01*
D02*
G37*
G36*
X19477D02*
X18957Y-251427D01*
X18451Y-251933D01*
X18235Y-252453D01*
X19477D01*
Y-251212D01*
D02*
G37*
G36*
X2237Y-248299D02*
X2035D01*
Y-253130D01*
X6866D01*
Y-252928D01*
X6503Y-251572D01*
X5801Y-250357D01*
X4809Y-249364D01*
X3593Y-248662D01*
X2237Y-248299D01*
D02*
G37*
G36*
X-17763D02*
X-17965D01*
Y-253130D01*
X-13134D01*
Y-252928D01*
X-13497Y-251572D01*
X-14199Y-250357D01*
X-15191Y-249364D01*
X-16407Y-248662D01*
X-17763Y-248299D01*
D02*
G37*
G36*
X-18965D02*
X-19166D01*
X-20522Y-248662D01*
X-21738Y-249364D01*
X-22730Y-250357D01*
X-23432Y-251572D01*
X-23795Y-252928D01*
Y-253130D01*
X-18965D01*
Y-248299D01*
D02*
G37*
G36*
X1035D02*
X834D01*
X-522Y-248662D01*
X-1738Y-249364D01*
X-2730Y-250357D01*
X-3432Y-251572D01*
X-3795Y-252928D01*
Y-253130D01*
X1035D01*
Y-248299D01*
D02*
G37*
G36*
X21718Y-253453D02*
X18235D01*
X18257Y-253505D01*
X17979Y-253921D01*
X14646D01*
Y-256488D01*
X19976D01*
X25307D01*
Y-253921D01*
X21974D01*
X21696Y-253505D01*
X21718Y-253453D01*
D02*
G37*
G36*
X6866Y-254130D02*
X2035D01*
Y-258961D01*
X2237D01*
X3593Y-258597D01*
X4809Y-257896D01*
X5801Y-256903D01*
X6503Y-255687D01*
X6866Y-254332D01*
Y-254130D01*
D02*
G37*
G36*
X1035D02*
X-3795D01*
Y-254332D01*
X-3432Y-255687D01*
X-2730Y-256903D01*
X-1738Y-257896D01*
X-522Y-258597D01*
X834Y-258961D01*
X1035D01*
Y-254130D01*
D02*
G37*
G36*
X-13134D02*
X-17965D01*
Y-258961D01*
X-17763D01*
X-16407Y-258597D01*
X-15191Y-257896D01*
X-14199Y-256903D01*
X-13497Y-255687D01*
X-13134Y-254332D01*
Y-254130D01*
D02*
G37*
G36*
X-18965D02*
X-23795D01*
Y-254332D01*
X-23432Y-255687D01*
X-22730Y-256903D01*
X-21738Y-257896D01*
X-20522Y-258597D01*
X-19166Y-258961D01*
X-18965D01*
Y-254130D01*
D02*
G37*
G36*
X25307Y-257488D02*
X20477D01*
Y-260055D01*
X25307D01*
Y-257488D01*
D02*
G37*
G36*
X19477D02*
X14646D01*
Y-259827D01*
X10906D01*
Y-261368D01*
X-3528D01*
Y-258693D01*
X-13402D01*
Y-268567D01*
X-3528D01*
Y-264223D01*
X10906D01*
Y-265764D01*
X12545D01*
Y-269439D01*
X9055D01*
X8509Y-269547D01*
X8046Y-269857D01*
X7736Y-270320D01*
X7628Y-270866D01*
Y-277937D01*
X6677D01*
Y-279281D01*
X2973D01*
X2907Y-278781D01*
X3593Y-278597D01*
X4809Y-277896D01*
X5801Y-276903D01*
X6503Y-275688D01*
X6866Y-274332D01*
Y-274130D01*
X1535D01*
Y-273630D01*
D01*
Y-274130D01*
X-3795D01*
Y-274332D01*
X-3432Y-275688D01*
X-2730Y-276903D01*
X-1738Y-277896D01*
X-522Y-278597D01*
X290Y-278815D01*
X224Y-279315D01*
X-213D01*
Y-286827D01*
X5725D01*
Y-282136D01*
X6677D01*
Y-283480D01*
X9286D01*
X9596Y-283858D01*
Y-287992D01*
X9705Y-288538D01*
X10014Y-289001D01*
X10477Y-289311D01*
X10679Y-289351D01*
X10844Y-289894D01*
X10411Y-290326D01*
X10272D01*
X9610Y-290600D01*
X9104Y-291106D01*
X8830Y-291768D01*
Y-292484D01*
X9104Y-293146D01*
X9610Y-293652D01*
X10272Y-293926D01*
X10988D01*
X11562Y-293688D01*
X11992Y-293520D01*
X12343Y-293874D01*
X12384Y-293935D01*
X12373Y-293961D01*
Y-294677D01*
X12263Y-294842D01*
X12165D01*
Y-299130D01*
Y-299364D01*
X14173D01*
X16181D01*
Y-299130D01*
Y-294842D01*
X16083D01*
X15973Y-294677D01*
Y-293961D01*
X15962Y-293935D01*
X16240Y-293520D01*
X17338D01*
Y-291551D01*
Y-287614D01*
Y-284433D01*
X16390D01*
X16018Y-283980D01*
X16112Y-283480D01*
X16945D01*
Y-277937D01*
X12189D01*
Y-282431D01*
X11433D01*
Y-277937D01*
X10483D01*
Y-272294D01*
X13973D01*
X14519Y-272185D01*
X14982Y-271876D01*
X15120Y-271669D01*
X17979D01*
X18257Y-272085D01*
X18235Y-272138D01*
X21718D01*
X21696Y-272085D01*
X21974Y-271669D01*
X25307D01*
Y-269102D01*
X19976D01*
Y-268602D01*
X19477D01*
Y-265535D01*
X17040D01*
Y-260055D01*
X19477D01*
Y-257488D01*
D02*
G37*
G36*
X25307Y-265535D02*
X20477D01*
Y-268102D01*
X25307D01*
Y-265535D01*
D02*
G37*
G36*
X2237Y-268299D02*
X2035D01*
Y-273130D01*
X6866D01*
Y-272928D01*
X6503Y-271572D01*
X5801Y-270357D01*
X4809Y-269364D01*
X3593Y-268663D01*
X2237Y-268299D01*
D02*
G37*
G36*
X-17763D02*
X-17965D01*
Y-273130D01*
X-13134D01*
Y-272928D01*
X-13497Y-271572D01*
X-14199Y-270357D01*
X-15191Y-269364D01*
X-16407Y-268663D01*
X-17763Y-268299D01*
D02*
G37*
G36*
X-18965D02*
X-19166D01*
X-20522Y-268663D01*
X-21738Y-269364D01*
X-22730Y-270357D01*
X-23432Y-271572D01*
X-23795Y-272928D01*
Y-273130D01*
X-18965D01*
Y-268299D01*
D02*
G37*
G36*
X1035D02*
X834D01*
X-522Y-268663D01*
X-1738Y-269364D01*
X-2730Y-270357D01*
X-3432Y-271572D01*
X-3795Y-272928D01*
Y-273130D01*
X1035D01*
Y-268299D01*
D02*
G37*
G36*
X21718Y-273138D02*
X20477D01*
Y-274379D01*
X20996Y-274164D01*
X21502Y-273657D01*
X21718Y-273138D01*
D02*
G37*
G36*
X19477D02*
X18235D01*
X18451Y-273657D01*
X18957Y-274164D01*
X19477Y-274379D01*
Y-273138D01*
D02*
G37*
G36*
X-13134Y-274130D02*
X-17965D01*
Y-278961D01*
X-17763D01*
X-16407Y-278597D01*
X-15191Y-277896D01*
X-14199Y-276903D01*
X-13497Y-275688D01*
X-13134Y-274332D01*
Y-274130D01*
D02*
G37*
G36*
X-18965D02*
X-23795D01*
Y-274332D01*
X-23432Y-275688D01*
X-22730Y-276903D01*
X-21738Y-277896D01*
X-20522Y-278597D01*
X-19166Y-278961D01*
X-18965D01*
Y-274130D01*
D02*
G37*
G36*
X27567Y-280936D02*
Y-282177D01*
X28808D01*
X28593Y-281658D01*
X28087Y-281151D01*
X27567Y-280936D01*
D02*
G37*
G36*
X26567D02*
X26047Y-281151D01*
X25541Y-281658D01*
X25326Y-282177D01*
X26567D01*
Y-280936D01*
D02*
G37*
G36*
X28808Y-283177D02*
X25326D01*
X25541Y-283697D01*
X25777Y-283933D01*
X25570Y-284433D01*
X24394D01*
Y-285524D01*
X27067D01*
X29740D01*
Y-284433D01*
X28564D01*
X28357Y-283933D01*
X28593Y-283697D01*
X28808Y-283177D01*
D02*
G37*
G36*
X-1756Y-279315D02*
X-7693D01*
Y-286827D01*
X-1756D01*
Y-279315D01*
D02*
G37*
G36*
X-4437Y-287976D02*
X-7693D01*
Y-291232D01*
X-4437D01*
Y-287976D01*
D02*
G37*
G36*
Y-292232D02*
X-7693D01*
Y-295488D01*
X-4437D01*
Y-292232D01*
D02*
G37*
G36*
X-23264Y-280680D02*
X-23980D01*
X-24642Y-280954D01*
X-25148Y-281461D01*
X-25422Y-282122D01*
Y-282838D01*
X-25148Y-283500D01*
X-24642Y-284006D01*
X-24227Y-284178D01*
Y-284719D01*
X-24642Y-284891D01*
X-25148Y-285398D01*
X-25422Y-286059D01*
Y-286775D01*
X-25148Y-287437D01*
X-24642Y-287943D01*
X-24227Y-288115D01*
Y-288656D01*
X-24642Y-288828D01*
X-25148Y-289335D01*
X-25422Y-289996D01*
Y-290712D01*
X-25148Y-291374D01*
X-24642Y-291880D01*
X-24227Y-292052D01*
Y-292593D01*
X-24642Y-292765D01*
X-25148Y-293272D01*
X-25422Y-293933D01*
Y-294649D01*
X-25148Y-295311D01*
X-24642Y-295817D01*
X-23980Y-296091D01*
X-23264D01*
X-22602Y-295817D01*
X-22507Y-295722D01*
X-21177D01*
Y-296276D01*
X-15634D01*
Y-291913D01*
X-17602D01*
Y-288992D01*
Y-285252D01*
X-15634D01*
Y-280890D01*
X-21177D01*
Y-281206D01*
X-22351D01*
X-22602Y-280954D01*
X-23264Y-280680D01*
D02*
G37*
G36*
X16181Y-300364D02*
X14673D01*
Y-302008D01*
X16181D01*
Y-300364D01*
D02*
G37*
G36*
X13673D02*
X12165D01*
Y-302008D01*
X13673D01*
Y-300364D01*
D02*
G37*
G36*
X-17763Y-301450D02*
X-17965D01*
Y-306281D01*
X-13134D01*
Y-306079D01*
X-13497Y-304724D01*
X-14199Y-303508D01*
X-15191Y-302516D01*
X-16407Y-301814D01*
X-17763Y-301450D01*
D02*
G37*
G36*
X2237D02*
X2035D01*
Y-306281D01*
X6866D01*
Y-306079D01*
X6503Y-304724D01*
X5801Y-303508D01*
X4809Y-302516D01*
X3593Y-301814D01*
X2237Y-301450D01*
D02*
G37*
G36*
X1035D02*
X834D01*
X-522Y-301814D01*
X-1738Y-302516D01*
X-2730Y-303508D01*
X-3432Y-304724D01*
X-3795Y-306079D01*
Y-306281D01*
X1035D01*
Y-301450D01*
D02*
G37*
G36*
X-18965D02*
X-19166D01*
X-20522Y-301814D01*
X-21738Y-302516D01*
X-22730Y-303508D01*
X-23432Y-304724D01*
X-23795Y-306079D01*
Y-306281D01*
X-18965D01*
Y-301450D01*
D02*
G37*
G36*
X20477Y-305345D02*
Y-306587D01*
X21718D01*
X21502Y-306067D01*
X20996Y-305561D01*
X20477Y-305345D01*
D02*
G37*
G36*
X19477D02*
X18957Y-305561D01*
X18451Y-306067D01*
X18235Y-306587D01*
X19477D01*
Y-305345D01*
D02*
G37*
G36*
X21718Y-307587D02*
X18235D01*
X18257Y-307639D01*
X17979Y-308055D01*
X14646D01*
Y-310622D01*
X19976D01*
X25307D01*
Y-308055D01*
X21974D01*
X21696Y-307639D01*
X21718Y-307587D01*
D02*
G37*
G36*
X6866Y-307281D02*
X2035D01*
Y-312112D01*
X2237D01*
X3593Y-311749D01*
X4809Y-311047D01*
X5801Y-310054D01*
X6503Y-308839D01*
X6866Y-307483D01*
Y-307281D01*
D02*
G37*
G36*
X1035D02*
X-3795D01*
Y-307483D01*
X-3432Y-308839D01*
X-2730Y-310054D01*
X-1738Y-311047D01*
X-522Y-311749D01*
X834Y-312112D01*
X1035D01*
Y-307281D01*
D02*
G37*
G36*
X-13134D02*
X-17965D01*
Y-312112D01*
X-17763D01*
X-16407Y-311749D01*
X-15191Y-311047D01*
X-14199Y-310054D01*
X-13497Y-308839D01*
X-13134Y-307483D01*
Y-307281D01*
D02*
G37*
G36*
X-18965D02*
X-23795D01*
Y-307483D01*
X-23432Y-308839D01*
X-22730Y-310054D01*
X-21738Y-311047D01*
X-20522Y-311749D01*
X-19166Y-312112D01*
X-18965D01*
Y-307281D01*
D02*
G37*
G36*
X25307Y-311622D02*
X20477D01*
Y-314189D01*
X25307D01*
Y-311622D01*
D02*
G37*
G36*
X5725Y-287976D02*
X-3437D01*
Y-291732D01*
X-3937D01*
D01*
X-3437D01*
Y-295488D01*
X1328D01*
Y-296063D01*
X1328Y-296063D01*
X1437Y-296609D01*
X1747Y-297072D01*
X8415Y-303741D01*
Y-312799D01*
X8415Y-312799D01*
X8524Y-313345D01*
X8833Y-313808D01*
X10064Y-315040D01*
X9873Y-315502D01*
X-3528D01*
Y-311844D01*
X-13402D01*
Y-321718D01*
X-3528D01*
Y-318357D01*
X10906D01*
Y-319898D01*
X12545D01*
Y-334006D01*
X3953D01*
Y-333055D01*
X-1591D01*
Y-337811D01*
X3953D01*
Y-336860D01*
X5537D01*
X5586Y-337361D01*
X5556Y-337367D01*
X5060Y-337698D01*
X4728Y-338194D01*
X4612Y-338779D01*
Y-339219D01*
X3953D01*
Y-338567D01*
X-1591D01*
Y-343323D01*
X-1923Y-343685D01*
X-3362D01*
Y-348244D01*
Y-351591D01*
X-3135D01*
X-2823Y-352091D01*
X-2981Y-352473D01*
Y-353189D01*
X-2707Y-353850D01*
X-2201Y-354357D01*
X-1539Y-354631D01*
X-823D01*
X-161Y-354357D01*
X345Y-353850D01*
X619Y-353189D01*
Y-352473D01*
X461Y-352091D01*
X773Y-351591D01*
X1000D01*
Y-351248D01*
X1500Y-350914D01*
X1597Y-350954D01*
Y-349213D01*
X2597D01*
Y-350954D01*
X3004Y-350785D01*
X3504Y-351005D01*
Y-351221D01*
X5147D01*
Y-349213D01*
X6148D01*
Y-351221D01*
X10669D01*
Y-350742D01*
X11290D01*
X11517Y-351081D01*
X12013Y-351413D01*
X12598Y-351529D01*
X16520D01*
Y-352181D01*
X24425D01*
Y-351529D01*
X26772D01*
X27357Y-351413D01*
X27853Y-351081D01*
X28185Y-350585D01*
X28301Y-350000D01*
Y-349830D01*
X28572Y-349177D01*
Y-348461D01*
X28298Y-347799D01*
X27791Y-347293D01*
X27777Y-347287D01*
X27738Y-347229D01*
X25115Y-344606D01*
X25307Y-344144D01*
X26454D01*
X27743Y-345433D01*
Y-345572D01*
X28017Y-346234D01*
X28523Y-346740D01*
X29185Y-347014D01*
X29901D01*
X30563Y-346740D01*
X31069Y-346234D01*
X31343Y-345572D01*
Y-344856D01*
X31069Y-344195D01*
X30563Y-343688D01*
X29901Y-343414D01*
X29762D01*
X28055Y-341707D01*
X27591Y-341398D01*
X27045Y-341289D01*
X27045Y-341289D01*
X26344D01*
X26152Y-340827D01*
X27778Y-339202D01*
X27917D01*
X28579Y-338928D01*
X29085Y-338421D01*
X29359Y-337760D01*
Y-337043D01*
X29085Y-336382D01*
X28579Y-335876D01*
X27917Y-335602D01*
X27201D01*
X26539Y-335876D01*
X26033Y-336382D01*
X25759Y-337043D01*
Y-337183D01*
X25084Y-337858D01*
X24622Y-337667D01*
Y-337189D01*
X23544D01*
X23337Y-336689D01*
X23573Y-336453D01*
X23788Y-335933D01*
X20306D01*
X20521Y-336453D01*
X20758Y-336689D01*
X20550Y-337189D01*
X19276D01*
Y-338280D01*
X21949D01*
Y-339157D01*
X19276D01*
Y-340370D01*
Y-342339D01*
Y-346276D01*
X22459D01*
X23540Y-347357D01*
X23349Y-347819D01*
X16520D01*
Y-348471D01*
X14239D01*
X14124Y-348193D01*
X13618Y-347687D01*
X12957Y-347413D01*
X12240D01*
X11587Y-347683D01*
X10669D01*
Y-347204D01*
X10055D01*
Y-346276D01*
X12220D01*
Y-344307D01*
Y-340370D01*
Y-337361D01*
X12220Y-337189D01*
X12584Y-336860D01*
X13973D01*
X14519Y-336752D01*
X14982Y-336442D01*
X15291Y-335979D01*
X15400Y-335433D01*
Y-325803D01*
X17979D01*
X18257Y-326219D01*
X18235Y-326272D01*
X21718D01*
X21696Y-326219D01*
X21974Y-325803D01*
X25307D01*
Y-323236D01*
X19976D01*
Y-322736D01*
X19477D01*
Y-319669D01*
X17040D01*
Y-314189D01*
X19477D01*
Y-311622D01*
X14646D01*
Y-313961D01*
X13023D01*
X11270Y-312208D01*
Y-303150D01*
X11161Y-302603D01*
X10852Y-302140D01*
X10852Y-302140D01*
X4662Y-295950D01*
X4853Y-295488D01*
X5725D01*
Y-287976D01*
D02*
G37*
G36*
X25307Y-319669D02*
X20477D01*
Y-322236D01*
X25307D01*
Y-319669D01*
D02*
G37*
G36*
X-17763Y-321450D02*
X-17965D01*
Y-326281D01*
X-13134D01*
Y-326079D01*
X-13497Y-324724D01*
X-14199Y-323508D01*
X-15191Y-322516D01*
X-16407Y-321814D01*
X-17763Y-321450D01*
D02*
G37*
G36*
X2237D02*
X2035D01*
Y-326281D01*
X6866D01*
Y-326079D01*
X6503Y-324724D01*
X5801Y-323508D01*
X4809Y-322516D01*
X3593Y-321814D01*
X2237Y-321450D01*
D02*
G37*
G36*
X1035D02*
X834D01*
X-522Y-321814D01*
X-1738Y-322516D01*
X-2730Y-323508D01*
X-3432Y-324724D01*
X-3795Y-326079D01*
Y-326281D01*
X1035D01*
Y-321450D01*
D02*
G37*
G36*
X-18965D02*
X-19166D01*
X-20522Y-321814D01*
X-21738Y-322516D01*
X-22730Y-323508D01*
X-23432Y-324724D01*
X-23795Y-326079D01*
Y-326281D01*
X-18965D01*
Y-321450D01*
D02*
G37*
G36*
X21718Y-327272D02*
X20477D01*
Y-328513D01*
X20996Y-328298D01*
X21502Y-327791D01*
X21718Y-327272D01*
D02*
G37*
G36*
X19477D02*
X18235D01*
X18451Y-327791D01*
X18957Y-328298D01*
X19477Y-328513D01*
Y-327272D01*
D02*
G37*
G36*
X6866Y-327281D02*
X2035D01*
Y-332112D01*
X2237D01*
X3593Y-331749D01*
X4809Y-331047D01*
X5801Y-330054D01*
X6503Y-328839D01*
X6866Y-327483D01*
Y-327281D01*
D02*
G37*
G36*
X1035D02*
X-3795D01*
Y-327483D01*
X-3432Y-328839D01*
X-2730Y-330054D01*
X-1738Y-331047D01*
X-522Y-331749D01*
X834Y-332112D01*
X1035D01*
Y-327281D01*
D02*
G37*
G36*
X-13134D02*
X-17965D01*
Y-332112D01*
X-17763D01*
X-16407Y-331749D01*
X-15191Y-331047D01*
X-14199Y-330054D01*
X-13497Y-328839D01*
X-13134Y-327483D01*
Y-327281D01*
D02*
G37*
G36*
X-18965D02*
X-23795D01*
Y-327483D01*
X-23432Y-328839D01*
X-22730Y-330054D01*
X-21738Y-331047D01*
X-20522Y-331749D01*
X-19166Y-332112D01*
X-18965D01*
Y-327281D01*
D02*
G37*
G36*
X-15634Y-333646D02*
X-21177D01*
Y-334301D01*
X-22406D01*
X-22602Y-334104D01*
X-23264Y-333830D01*
X-23980D01*
X-24642Y-334104D01*
X-25148Y-334610D01*
X-25422Y-335272D01*
Y-335988D01*
X-25148Y-336649D01*
X-24642Y-337156D01*
X-24227Y-337328D01*
Y-337869D01*
X-24642Y-338041D01*
X-25148Y-338547D01*
X-25422Y-339209D01*
Y-339925D01*
X-25148Y-340586D01*
X-24691Y-341043D01*
X-25148Y-341500D01*
X-25422Y-342162D01*
Y-342878D01*
X-25148Y-343539D01*
X-24642Y-344046D01*
X-23980Y-344320D01*
X-23264D01*
X-22734Y-344100D01*
X-21768D01*
Y-345291D01*
X-21177D01*
Y-349031D01*
X-20415D01*
X-20401Y-349051D01*
Y-349767D01*
X-20127Y-350429D01*
X-19621Y-350935D01*
X-18959Y-351209D01*
X-18243D01*
X-17582Y-350935D01*
X-17075Y-350429D01*
X-16801Y-349767D01*
Y-349051D01*
X-16788Y-349031D01*
X-15634D01*
Y-344669D01*
X-17602D01*
Y-341748D01*
Y-338008D01*
X-15634D01*
Y-333646D01*
D02*
G37*
G36*
X22547Y-333692D02*
Y-334933D01*
X23788D01*
X23573Y-334414D01*
X23067Y-333907D01*
X22547Y-333692D01*
D02*
G37*
G36*
X21547D02*
X21028Y-333907D01*
X20521Y-334414D01*
X20306Y-334933D01*
X21547D01*
Y-333692D01*
D02*
G37*
G36*
X496421Y-143476D02*
X495705D01*
X495043Y-143750D01*
X494537Y-144256D01*
X494263Y-144918D01*
Y-145634D01*
X494537Y-146295D01*
X495043Y-146801D01*
X495705Y-147076D01*
X496421D01*
X497083Y-146801D01*
X497589Y-146295D01*
X497863Y-145634D01*
Y-144918D01*
X497589Y-144256D01*
X497083Y-143750D01*
X496421Y-143476D01*
D02*
G37*
G36*
X500752Y-143869D02*
X500036D01*
X499374Y-144143D01*
X498868Y-144650D01*
X498594Y-145311D01*
Y-146027D01*
X498868Y-146689D01*
X499374Y-147195D01*
X500036Y-147469D01*
X500752D01*
X501413Y-147195D01*
X501920Y-146689D01*
X502194Y-146027D01*
Y-145311D01*
X501920Y-144650D01*
X501413Y-144143D01*
X500752Y-143869D01*
D02*
G37*
G36*
X492090Y-143476D02*
X491374D01*
X490713Y-143750D01*
X490206Y-144256D01*
X489932Y-144918D01*
Y-145634D01*
X490206Y-146295D01*
X490713Y-146801D01*
X491128Y-146974D01*
Y-147515D01*
X490713Y-147687D01*
X490206Y-148193D01*
X489932Y-148855D01*
Y-149571D01*
X490206Y-150232D01*
X490713Y-150739D01*
X491374Y-151013D01*
X492090D01*
X492752Y-150739D01*
X493258Y-150232D01*
X493532Y-149571D01*
Y-148855D01*
X493258Y-148193D01*
X492752Y-147687D01*
X492337Y-147515D01*
Y-146974D01*
X492752Y-146801D01*
X493258Y-146295D01*
X493532Y-145634D01*
Y-144918D01*
X493258Y-144256D01*
X492752Y-143750D01*
X492090Y-143476D01*
D02*
G37*
G36*
X496421Y-242295D02*
X495705D01*
X495043Y-242568D01*
X494537Y-243075D01*
X494263Y-243737D01*
Y-244453D01*
X494537Y-245114D01*
X495043Y-245620D01*
X495705Y-245895D01*
X496421D01*
X497083Y-245620D01*
X497589Y-245114D01*
X497863Y-244453D01*
Y-243737D01*
X497589Y-243075D01*
X497083Y-242568D01*
X496421Y-242295D01*
D02*
G37*
G36*
X496027Y-253712D02*
X495311D01*
X494650Y-253986D01*
X494143Y-254492D01*
X493869Y-255154D01*
Y-255870D01*
X494143Y-256531D01*
X494650Y-257038D01*
X495311Y-257312D01*
X496027D01*
X496689Y-257038D01*
X497195Y-256531D01*
X497469Y-255870D01*
Y-255154D01*
X497195Y-254492D01*
X496689Y-253986D01*
X496027Y-253712D01*
D02*
G37*
G36*
X79291Y-146780D02*
X77245D01*
X75223Y-147100D01*
X73277Y-147732D01*
X71454Y-148661D01*
X69799Y-149864D01*
X68352Y-151311D01*
X67149Y-152966D01*
X66220Y-154789D01*
X65588Y-156735D01*
X65268Y-158756D01*
Y-159926D01*
X63268Y-160463D01*
X62928Y-159955D01*
X62093Y-159119D01*
X61110Y-158462D01*
X60018Y-158010D01*
X58859Y-157780D01*
X57677D01*
X56518Y-158010D01*
X55426Y-158462D01*
X54443Y-159119D01*
X53607Y-159955D01*
X52951Y-160937D01*
X52498Y-162029D01*
X52268Y-163189D01*
Y-164371D01*
X52498Y-165530D01*
X52951Y-166622D01*
X53607Y-167604D01*
X54443Y-168440D01*
X55426Y-169097D01*
X56518Y-169549D01*
X57677Y-169780D01*
X58859D01*
X60018Y-169549D01*
X61110Y-169097D01*
X62093Y-168440D01*
X62928Y-167604D01*
X63585Y-166622D01*
X64037Y-165530D01*
X64161Y-164906D01*
X66220Y-164770D01*
X67149Y-166593D01*
X68352Y-168248D01*
X69799Y-169695D01*
X71454Y-170898D01*
X73277Y-171827D01*
X75223Y-172459D01*
X77245Y-172780D01*
X79291D01*
X81312Y-172459D01*
X83258Y-171827D01*
X85081Y-170898D01*
X86737Y-169695D01*
X88183Y-168248D01*
X89386Y-166593D01*
X90315Y-164770D01*
X90948Y-162824D01*
X91268Y-160803D01*
Y-158756D01*
X90948Y-156735D01*
X90315Y-154789D01*
X89386Y-152966D01*
X88183Y-151311D01*
X86737Y-149864D01*
X85081Y-148661D01*
X83258Y-147732D01*
X81312Y-147100D01*
X79291Y-146780D01*
D02*
G37*
G36*
X219293Y-156321D02*
X217853D01*
X216440Y-156602D01*
X215110Y-157153D01*
X213913Y-157953D01*
X212894Y-158971D01*
X212094Y-160169D01*
X211543Y-161499D01*
X211526Y-161583D01*
X209356Y-162241D01*
X209079Y-161964D01*
X207424Y-160761D01*
X205601Y-159832D01*
X203654Y-159200D01*
X201633Y-158879D01*
X199587D01*
X197566Y-159200D01*
X195620Y-159832D01*
X193797Y-160761D01*
X192141Y-161964D01*
X190694Y-163411D01*
X189492Y-165066D01*
X188563Y-166889D01*
X187930Y-168835D01*
X187610Y-170856D01*
Y-172903D01*
X187930Y-174924D01*
X188563Y-176870D01*
X189492Y-178693D01*
X190694Y-180349D01*
X192141Y-181795D01*
X193797Y-182998D01*
X195620Y-183927D01*
X197566Y-184559D01*
X199587Y-184880D01*
X201633D01*
X203654Y-184559D01*
X205601Y-183927D01*
X207424Y-182998D01*
X209079Y-181795D01*
X210526Y-180349D01*
X211729Y-178693D01*
X212658Y-176870D01*
X213290Y-174924D01*
X213610Y-172903D01*
Y-171513D01*
X214444Y-170733D01*
X214852Y-170493D01*
X215546Y-170291D01*
X216440Y-170661D01*
X217853Y-170942D01*
X219293D01*
X220705Y-170661D01*
X222036Y-170110D01*
X223233Y-169310D01*
X224251Y-168292D01*
X225051Y-167094D01*
X225603Y-165764D01*
X225883Y-164351D01*
Y-162911D01*
X225603Y-161499D01*
X225051Y-160169D01*
X224251Y-158971D01*
X223233Y-157953D01*
X222036Y-157153D01*
X220705Y-156602D01*
X219293Y-156321D01*
D02*
G37*
G36*
X76791Y-308622D02*
X74745D01*
X72724Y-308942D01*
X70777Y-309575D01*
X68954Y-310503D01*
X67299Y-311706D01*
X65852Y-313153D01*
X64649Y-314809D01*
X64108Y-315870D01*
X62725Y-316683D01*
X61581Y-316742D01*
X60863Y-316444D01*
X59450Y-316163D01*
X58010D01*
X56598Y-316444D01*
X55267Y-316995D01*
X54070Y-317795D01*
X53052Y-318814D01*
X52252Y-320011D01*
X51701Y-321342D01*
X51420Y-322754D01*
Y-324194D01*
X51701Y-325606D01*
X52252Y-326937D01*
X53052Y-328134D01*
X54070Y-329153D01*
X55267Y-329953D01*
X56598Y-330504D01*
X58010Y-330785D01*
X59450D01*
X60863Y-330504D01*
X62193Y-329953D01*
X62971Y-329433D01*
X63426Y-329162D01*
X65611Y-329760D01*
X65852Y-330091D01*
X67299Y-331538D01*
X68954Y-332741D01*
X70777Y-333670D01*
X72724Y-334302D01*
X74745Y-334622D01*
X76791D01*
X78812Y-334302D01*
X80758Y-333670D01*
X82581Y-332741D01*
X84237Y-331538D01*
X85684Y-330091D01*
X86886Y-328435D01*
X87815Y-326612D01*
X88448Y-324666D01*
X88768Y-322645D01*
Y-320599D01*
X88448Y-318578D01*
X87815Y-316632D01*
X86886Y-314809D01*
X85684Y-313153D01*
X84237Y-311706D01*
X82581Y-310503D01*
X80758Y-309575D01*
X78812Y-308942D01*
X76791Y-308622D01*
D02*
G37*
G36*
X201899Y-302719D02*
X199853D01*
X197832Y-303039D01*
X195886Y-303671D01*
X194062Y-304600D01*
X192407Y-305803D01*
X190960Y-307250D01*
X189757Y-308906D01*
X188828Y-310729D01*
X188196Y-312675D01*
X187876Y-314696D01*
Y-316742D01*
X188196Y-318763D01*
X188828Y-320709D01*
X189757Y-322532D01*
X190960Y-324188D01*
X192407Y-325635D01*
X194062Y-326837D01*
X194495Y-327058D01*
X194663Y-327513D01*
X194577Y-329344D01*
X194207Y-329591D01*
X193371Y-330427D01*
X193290Y-330549D01*
X193197Y-330594D01*
X191055D01*
X190962Y-330549D01*
X190881Y-330427D01*
X190045Y-329591D01*
X189063Y-328935D01*
X187971Y-328483D01*
X186811Y-328252D01*
X185629D01*
X184470Y-328483D01*
X183378Y-328935D01*
X182396Y-329591D01*
X181560Y-330427D01*
X181397Y-330672D01*
X181043Y-330812D01*
X179398D01*
X179044Y-330672D01*
X178881Y-330427D01*
X178045Y-329591D01*
X177062Y-328935D01*
X175971Y-328483D01*
X174811Y-328252D01*
X173629D01*
X172470Y-328483D01*
X171378Y-328935D01*
X170396Y-329591D01*
X169560Y-330427D01*
X169397Y-330672D01*
X169043Y-330812D01*
X167398D01*
X167044Y-330672D01*
X166881Y-330427D01*
X166045Y-329591D01*
X165062Y-328935D01*
X163971Y-328483D01*
X162811Y-328252D01*
X161629D01*
X160470Y-328483D01*
X159378Y-328935D01*
X158396Y-329591D01*
X157560Y-330427D01*
X156903Y-331410D01*
X156451Y-332502D01*
X156220Y-333661D01*
Y-334843D01*
X156451Y-336002D01*
X156903Y-337094D01*
X157560Y-338077D01*
X158396Y-338913D01*
X159378Y-339569D01*
X160470Y-340021D01*
X161629Y-340252D01*
X162811D01*
X163971Y-340021D01*
X165062Y-339569D01*
X166045Y-338913D01*
X166881Y-338077D01*
X167044Y-337832D01*
X167398Y-337692D01*
X169043D01*
X169397Y-337832D01*
X169560Y-338077D01*
X170396Y-338913D01*
X171378Y-339569D01*
X172470Y-340021D01*
X173629Y-340252D01*
X174811D01*
X175971Y-340021D01*
X177062Y-339569D01*
X178045Y-338913D01*
X178881Y-338077D01*
X179044Y-337832D01*
X179398Y-337692D01*
X181043D01*
X181397Y-337832D01*
X181560Y-338077D01*
X182396Y-338913D01*
X183378Y-339569D01*
X184470Y-340021D01*
X185629Y-340252D01*
X186811D01*
X187971Y-340021D01*
X189063Y-339569D01*
X190045Y-338913D01*
X190881Y-338077D01*
X190962Y-337955D01*
X191055Y-337910D01*
X193197D01*
X193290Y-337955D01*
X193371Y-338077D01*
X194207Y-338913D01*
X195189Y-339569D01*
X196281Y-340021D01*
X197441Y-340252D01*
X198623D01*
X199782Y-340021D01*
X200874Y-339569D01*
X201856Y-338913D01*
X202692Y-338077D01*
X202773Y-337955D01*
X202866Y-337910D01*
X205008D01*
X205101Y-337955D01*
X205182Y-338077D01*
X206018Y-338913D01*
X207000Y-339569D01*
X208092Y-340021D01*
X209252Y-340252D01*
X210434D01*
X211593Y-340021D01*
X212685Y-339569D01*
X213667Y-338913D01*
X214503Y-338077D01*
X215160Y-337094D01*
X215612Y-336002D01*
X215843Y-334843D01*
Y-333661D01*
X215612Y-332502D01*
X215160Y-331410D01*
X214503Y-330427D01*
X213667Y-329591D01*
X212685Y-328935D01*
X211593Y-328483D01*
X210434Y-328252D01*
X209252D01*
X209105Y-328281D01*
X208284Y-326405D01*
X209345Y-325635D01*
X210792Y-324188D01*
X211995Y-322532D01*
X212923Y-320709D01*
X213556Y-318763D01*
X213876Y-316742D01*
Y-314696D01*
X213556Y-312675D01*
X212923Y-310729D01*
X211995Y-308906D01*
X210792Y-307250D01*
X209345Y-305803D01*
X207689Y-304600D01*
X205866Y-303671D01*
X203920Y-303039D01*
X201899Y-302719D01*
D02*
G37*
%LPD*%
D11*
X268922Y-392732D02*
G03*
X268428Y-391417I-2000J-0D01*
G01*
X218189Y-393476D02*
G03*
X217391Y-391877I-2000J-0D01*
G01*
X124016Y-110462D02*
X128459D01*
X124016D02*
Y-110236D01*
X262456Y-113189D02*
Y-108080D01*
X262724Y-107813D01*
X268922Y-392732D02*
X268922D01*
Y-392732D02*
Y-392732D01*
X281201Y-404080D02*
Y-390009D01*
X268922Y-401057D02*
Y-392732D01*
X251378Y-390009D02*
X253223Y-391854D01*
X241811Y-404100D02*
Y-397250D01*
X226002Y-404039D02*
Y-390783D01*
X218189Y-393476D02*
Y-393476D01*
X218189D02*
X218189D01*
Y-404100D02*
Y-393476D01*
X206213Y-403935D02*
Y-391498D01*
X174882Y-404100D02*
Y-390659D01*
X163006Y-404035D02*
Y-390730D01*
X66102Y-48355D02*
X85827D01*
X163006Y-404035D02*
X163071Y-404100D01*
X251456Y-390009D02*
X255217D01*
X251378D02*
X251456D01*
X267204D02*
X268428Y-391417D01*
X216162Y-390947D02*
X217391Y-391877D01*
X281181Y-404100D02*
X281201Y-404080D01*
X235144Y-390416D02*
X240536D01*
X235230Y-390502D02*
X236624D01*
X235144Y-390416D02*
X235230Y-390502D01*
X241707Y-397146D02*
X241811Y-397250D01*
X240536Y-390416D02*
X241707Y-391587D01*
X268922Y-401057D02*
X269291Y-401427D01*
X226002Y-390783D02*
X226063Y-390722D01*
X257111Y-401057D02*
Y-391904D01*
X206213Y-403935D02*
X206378Y-404100D01*
X255217Y-390009D02*
X257111Y-391904D01*
X253223Y-401107D02*
X253543Y-401427D01*
X253223Y-401107D02*
Y-391854D01*
X205315Y-390600D02*
X206213Y-391498D01*
X236624Y-390502D02*
X237795Y-391673D01*
X241707Y-401402D02*
X241732Y-401427D01*
X241707Y-401402D02*
Y-397146D01*
X237795Y-401427D02*
Y-391673D01*
X174882Y-390659D02*
X174941Y-390600D01*
X202441D02*
X205315D01*
X257111Y-401057D02*
X257480Y-401427D01*
X241707Y-397146D02*
Y-391587D01*
X159134Y-404100D02*
Y-391118D01*
X155035Y-389506D02*
X156116Y-388425D01*
X155197Y-389669D02*
X156441Y-388425D01*
X152964Y-389506D02*
X155035D01*
X151260Y-404100D02*
Y-391210D01*
X155197Y-404100D02*
Y-389669D01*
X156116Y-388425D02*
X156441D01*
X151260Y-391210D02*
X152964Y-389506D01*
D16*
X262006Y-387255D02*
G03*
X261417Y-388680I1428J-1424D01*
G01*
X265354Y-387729D02*
G03*
X265158Y-387253I-672J0D01*
G01*
X373760Y-345287D02*
G03*
X374114Y-346144I1212J0D01*
G01*
X246328Y-386993D02*
G03*
X246293Y-387066I432J-252D01*
G01*
X246144Y-387379D02*
G03*
X246227Y-387239I-384J320D01*
G01*
X246143Y-387382D02*
G03*
X245669Y-388680I1543J-1298D01*
G01*
X249606Y-387729D02*
G03*
X249410Y-387253I-672J0D01*
G01*
X371359Y-346144D02*
G03*
X371791Y-345101I-1043J1043D01*
G01*
X365465Y-343770D02*
G03*
X364666Y-345700I1930J-1930D01*
G01*
X367422Y-346144D02*
G03*
X367854Y-345101I-1043J1043D01*
G01*
X365465Y-343770D02*
G03*
X365886Y-342755I-1015J1015D01*
G01*
X354429Y-343782D02*
G03*
X356043Y-339888I-3894J3894D01*
G01*
X354429Y-343782D02*
G03*
X354036Y-344733I950J-950D01*
G01*
X353248Y-342995D02*
G03*
X354075Y-341000I-1995J1995D01*
G01*
X352115Y-344128D02*
G03*
X351280Y-346144I2016J-2016D01*
G01*
X361516Y-342601D02*
G03*
X360729Y-344502I1901J-1901D01*
G01*
X229921Y-388679D02*
G03*
X229331Y-387253I-2016J0D01*
G01*
X359365Y-342784D02*
G03*
X359364Y-342785I3360J-3360D01*
G01*
D02*
G03*
X357973Y-346144I3361J-3359D01*
G01*
X232480Y-389290D02*
G03*
X233268Y-391191I2688J0D01*
G01*
X233858Y-392616D02*
G03*
X233268Y-391191I-2016J0D01*
G01*
X361516Y-342601D02*
G03*
X361949Y-341557I-1044J1044D01*
G01*
X359548Y-342601D02*
G03*
X359980Y-341558I-1043J1043D01*
G01*
X212795Y-387253D02*
G03*
X210236Y-393432I6178J-6178D01*
G01*
X215945Y-387253D02*
G03*
X214173Y-391531I4277J-4277D01*
G01*
X379665Y-343385D02*
G03*
X380807Y-346144I3902J0D01*
G01*
X377658D02*
G03*
X377697Y-346051I-94J94D01*
G01*
X373760Y-327679D02*
G03*
X374114Y-328034I355J0D01*
G01*
X371359D02*
G03*
X371791Y-327602I0J432D01*
G01*
X249641Y-403994D02*
G03*
X249685Y-404100I150J0D01*
G01*
X248741Y-401821D02*
G03*
X249685Y-404100I3223J0D01*
G01*
X232741Y-401213D02*
G03*
X233937Y-404100I4083J0D01*
G01*
X229041Y-401785D02*
G03*
X230000Y-404100I3274J0D01*
G01*
X213341Y-401901D02*
G03*
X214252Y-404100I3110J0D01*
G01*
X355761Y-322160D02*
X356003Y-321918D01*
X355761Y-324979D02*
Y-322160D01*
X355729Y-325012D02*
X355761Y-324979D01*
X355729Y-329472D02*
Y-325012D01*
Y-329472D02*
X356299Y-330043D01*
Y-330315D02*
Y-330043D01*
X367854Y-321841D02*
X367962Y-321949D01*
X261417Y-401427D02*
Y-388680D01*
X365886Y-325505D02*
Y-321841D01*
X265354Y-401427D02*
Y-387729D01*
X367962Y-330167D02*
X368110Y-330315D01*
X367962Y-330167D02*
Y-321949D01*
X365886Y-325505D02*
X366117Y-325736D01*
Y-329255D02*
Y-325736D01*
X365354Y-330017D02*
X366117Y-329255D01*
X365354Y-330315D02*
Y-330017D01*
X373760Y-345287D02*
Y-337785D01*
X246328Y-386993D02*
X246338Y-386976D01*
X246227Y-387239D02*
X246293Y-387066D01*
X246143Y-387382D02*
X246144Y-387379D01*
X245669Y-401427D02*
Y-388680D01*
X371791Y-345101D02*
Y-337785D01*
X249606Y-401427D02*
Y-387729D01*
X246338Y-386976D02*
X246339Y-386975D01*
X367854Y-345101D02*
Y-337785D01*
X364666Y-345700D02*
X364666Y-345703D01*
X365886Y-342755D02*
Y-337785D01*
X364666Y-346144D02*
Y-345703D01*
X356043Y-339888D02*
Y-337785D01*
X354036Y-346144D02*
Y-344733D01*
X354075Y-341000D02*
Y-337785D01*
X352115Y-344128D02*
X353248Y-342995D01*
X361949Y-341557D02*
Y-337785D01*
X360729Y-346144D02*
Y-344502D01*
X229921Y-401427D02*
Y-388679D01*
X359980Y-341558D02*
Y-337785D01*
X359365Y-342784D02*
X359548Y-342601D01*
X359364Y-342785D02*
X359365Y-342784D01*
X232480Y-389290D02*
Y-387253D01*
X233858Y-401427D02*
Y-392616D01*
X210236Y-401427D02*
Y-393432D01*
X354075Y-329486D02*
Y-321841D01*
X214173Y-401427D02*
Y-391531D01*
X353543Y-330017D02*
X354075Y-329486D01*
X353543Y-330315D02*
Y-330017D01*
X361949Y-326084D02*
Y-321841D01*
X359796Y-322024D02*
X359980Y-321841D01*
X361949Y-326084D02*
X362408Y-326544D01*
Y-326841D02*
Y-326544D01*
X359796Y-326697D02*
Y-322024D01*
X359652Y-326841D02*
X359796Y-326697D01*
X377697Y-346051D02*
Y-337785D01*
X379665Y-343385D02*
Y-337785D01*
X373760Y-327679D02*
Y-321841D01*
X371791D02*
X371822Y-321872D01*
X371791Y-327602D02*
Y-321841D01*
X245748Y-404100D02*
X246041Y-403807D01*
X245541Y-403893D02*
X245748Y-404100D01*
X264641Y-403308D02*
X265433Y-404100D01*
X261496D02*
X262241Y-403355D01*
D17*
X-4724Y-283071D02*
X-4724D01*
D18*
X178740Y-390551D02*
X181534Y-387757D01*
X178740Y-401427D02*
Y-390551D01*
X61417Y-5709D02*
Y231D01*
X61811Y625D01*
Y787D01*
X500394Y-262402D02*
Y-257140D01*
X500049Y-256796D02*
X500394Y-257140D01*
X500049Y-256796D02*
Y-256633D01*
X128459Y-116147D02*
Y-110462D01*
X127981Y-124314D02*
Y-116147D01*
X128459D01*
X128523D01*
X84981Y-132963D02*
X85044D01*
Y-139557D02*
Y-132963D01*
X94135Y-123809D02*
X100729D01*
X84981Y-114655D02*
Y-108061D01*
X64903D02*
X71792D01*
Y-117904D02*
Y-108061D01*
X58407Y-137589D02*
Y-133652D01*
X44134Y-115080D02*
X44296D01*
X44757Y-115541D01*
X47777D01*
X66462Y-124120D02*
X69806D01*
X70117Y-123809D01*
X64312Y-126270D02*
X66462Y-124120D01*
X57422Y-128927D02*
Y-126565D01*
Y-125581D01*
Y-126565D02*
X63918D01*
X64903Y-108061D02*
Y-103730D01*
X58210Y-108061D02*
Y-108061D01*
X50926D02*
Y-103730D01*
X64903D01*
X70117Y-123809D02*
X75828D01*
X71792Y-117904D02*
X75828D01*
X568307Y-297736D02*
Y-292126D01*
X570276Y-297736D02*
Y-292126D01*
X546654Y-297342D02*
Y-292126D01*
X540748Y-297342D02*
Y-292126D01*
X562402Y-297736D02*
Y-292126D01*
X523032Y-297736D02*
Y-292126D01*
X517126Y-298130D02*
Y-292126D01*
X168898Y-43898D02*
X174114D01*
X168898Y-49803D02*
X174114D01*
X168504Y-26181D02*
X174114D01*
X168110Y-20276D02*
X174114D01*
X168504Y-32087D02*
X174114D01*
X168504Y-65551D02*
X174114D01*
X168504Y-37992D02*
X174114D01*
X168504Y-71457D02*
X174114D01*
X168504Y-73425D02*
X174114D01*
X183465Y11417D02*
X206693D01*
X178347Y16535D02*
X183465Y11417D01*
X157874Y16535D02*
X178347D01*
X151782Y10443D02*
X157874Y16535D01*
X148425Y-98819D02*
X152326D01*
X492520Y-259449D02*
Y-256798D01*
X486221Y-265748D02*
X492520Y-259449D01*
X578740Y-192520D02*
X579134Y-192913D01*
X583858D01*
X-18601Y-349409D02*
Y-346850D01*
X-18406Y-70866D02*
X-11651D01*
X-18406D02*
Y-70669D01*
Y-113976D02*
X-9843D01*
X150233Y-119882D02*
X150331Y-119783D01*
X156975D01*
X157073Y-119685D01*
X295669Y-191339D02*
Y-186781D01*
X285827Y-183957D02*
X292845D01*
X295669Y-186781D01*
X226378Y-32677D02*
X239764D01*
X31693Y-1969D02*
X36614D01*
X230594Y-242799D02*
Y-242515D01*
X224941Y-240680D02*
X228759D01*
X230594Y-242515D01*
Y-242799D02*
X230709Y-242913D01*
X171055Y-119496D02*
X173228Y-117323D01*
X169377Y-119685D02*
X169565Y-119496D01*
X171055D01*
X204193Y-112795D02*
Y-107421D01*
X396850Y-252461D02*
X401575D01*
X390945D02*
X396850D01*
X386614D02*
X390945D01*
X381890Y-254331D02*
X383760Y-252461D01*
X386614D01*
X471662Y-76378D02*
X476968D01*
X462992Y-76378D02*
X462992Y-76378D01*
X457480Y-76378D02*
X462992D01*
X605905Y-186107D02*
X611614D01*
X606310Y-150000D02*
X608121Y-148189D01*
X609449D01*
X600591Y-150000D02*
X606310D01*
X581890Y-235925D02*
X584744Y-233071D01*
X597835D01*
X584749Y-225197D02*
X586323Y-226772D01*
X597835D01*
X584646Y-225197D02*
X584749D01*
X591040Y-220472D02*
X597835D01*
X590350Y-221161D02*
X591040Y-220472D01*
X590188Y-221161D02*
X590350D01*
X597441Y-233465D02*
X597835Y-233071D01*
X603740Y-226772D02*
Y-220472D01*
Y-233071D02*
Y-226772D01*
Y-220472D02*
X608661D01*
X407923Y-219636D02*
Y-216585D01*
Y-219636D02*
X407972Y-219685D01*
X407874Y-216535D02*
X407923Y-216585D01*
X407972Y-224016D02*
Y-219685D01*
X408957Y-237992D02*
Y-233268D01*
X408760Y-238189D02*
X408957Y-237992D01*
Y-233268D02*
X409154Y-233071D01*
X598401Y-83469D02*
X598406Y-83465D01*
X598397Y-88288D02*
X598401Y-88283D01*
Y-83469D01*
X603474Y-87726D02*
Y-83534D01*
X603406Y-83465D02*
X603474Y-83534D01*
Y-87726D02*
X603543Y-87795D01*
X387894Y-245965D02*
X390945Y-249016D01*
X428300Y-187842D02*
X428346Y-187795D01*
X428300Y-192653D02*
Y-187842D01*
X189764Y-91929D02*
Y-88189D01*
X151772Y10433D02*
X151782Y10443D01*
X151772Y6094D02*
Y10433D01*
X482874Y-265748D02*
X486221D01*
X479331Y-298237D02*
Y-294626D01*
X477362Y-313767D02*
Y-309637D01*
X569291Y-262402D02*
Y-256791D01*
X534828Y-297176D02*
Y-292140D01*
X534842Y-292126D01*
X534814Y-297190D02*
X534828Y-297176D01*
X528937Y-292126D02*
X528949Y-292138D01*
Y-296829D02*
X528960Y-296841D01*
X528949Y-296829D02*
Y-292138D01*
X503346Y-297967D02*
Y-292126D01*
X501279Y-298031D02*
Y-292224D01*
X571260Y-262402D02*
Y-256791D01*
X502362Y-262402D02*
Y-257185D01*
X504331Y-262402D02*
Y-257185D01*
X203839Y-72441D02*
X209449D01*
X203839Y-7480D02*
X209055D01*
X203839Y-5512D02*
X209055D01*
X203839Y-3543D02*
X209449D01*
X203839Y-74410D02*
X209449D01*
X168209Y-4429D02*
X174016D01*
X168273Y-6496D02*
X174114D01*
X-18601Y-346850D02*
X-18406D01*
X98228Y-99606D02*
Y-92126D01*
X97253Y-99606D02*
X98228D01*
X83465Y-92126D02*
Y-87795D01*
Y-92126D02*
X92323D01*
X87795Y-99606D02*
X93299D01*
X608405Y-70079D02*
Y-62205D01*
X600197Y-57480D02*
Y-52362D01*
Y-57480D02*
X603406D01*
Y-62205D02*
Y-57480D01*
X589764Y-62205D02*
Y-52362D01*
Y-62205D02*
X598406D01*
X238199Y-138967D02*
Y-132293D01*
X238209Y-132283D01*
X238189Y-138976D02*
X238199Y-138967D01*
X214173Y-107087D02*
X214193Y-107106D01*
Y-112795D02*
Y-107106D01*
X133099Y-124314D02*
Y-119984D01*
X135658Y-132385D02*
X140070D01*
X148425Y-104336D02*
X148425D01*
X153150Y-99643D02*
Y-99606D01*
X152326Y-98819D02*
X153150Y-99643D01*
Y-99691D02*
Y-99643D01*
Y-103459D02*
Y-103412D01*
X153947Y-100488D02*
X155973D01*
X153150Y-99691D02*
X153947Y-100488D01*
X155973D02*
X157050Y-101565D01*
X153150Y-99606D02*
X153973Y-98782D01*
X154058D02*
X154558Y-98282D01*
X153973Y-98782D02*
X154058D01*
X154558Y-98282D02*
X157482D01*
X159189Y-99990D01*
X159390D01*
X157050Y-101565D02*
X159390D01*
X158268Y-107480D02*
X159390Y-106358D01*
Y-103139D01*
X165287Y-102338D02*
Y-100132D01*
X164513Y-103112D02*
X165287Y-102338D01*
X163472Y-103112D02*
X164513D01*
X163445Y-103139D02*
X163472Y-103112D01*
X168110Y-103937D02*
Y-103805D01*
X163472Y-100017D02*
X165172D01*
X165287Y-100132D02*
X168110D01*
X163445Y-99990D02*
X163472Y-100017D01*
X165172D02*
X165287Y-100132D01*
X161417Y-95276D02*
X161417Y-95276D01*
Y-101565D02*
Y-95276D01*
X161417Y-107480D02*
X161417Y-107480D01*
Y-101565D01*
X152631Y-127362D02*
X154402Y-125591D01*
X157073D01*
X150233Y-127362D02*
X152631D01*
X152904Y-124213D02*
X153495Y-123622D01*
X157073D01*
X153225Y-121747D02*
X153272Y-121700D01*
X157027D01*
X157073Y-121653D01*
X152398Y-117717D02*
X157073D01*
X156926Y-111798D02*
Y-111614D01*
Y-111798D02*
X159330Y-114202D01*
X159513D01*
X160272Y-114961D01*
Y-117471D02*
Y-114961D01*
X164209Y-117471D02*
Y-114836D01*
X166178Y-117471D02*
Y-117043D01*
X166185Y-117035D02*
X166588D01*
X167182Y-116442D02*
Y-111988D01*
X168343Y-110827D01*
X166588Y-117035D02*
X167182Y-116442D01*
X166178Y-117043D02*
X166185Y-117035D01*
X160075Y-112402D02*
X162241Y-114567D01*
Y-117471D02*
Y-114567D01*
X171689Y-125591D02*
X173461Y-127362D01*
X169377Y-125591D02*
X171689D01*
X164209Y-138583D02*
X165587Y-139961D01*
X164209Y-138583D02*
Y-135679D01*
X100729Y-123872D02*
Y-123809D01*
X56693Y-5709D02*
Y1060D01*
X61417Y-35741D02*
Y-27362D01*
X37402Y-43355D02*
X44842D01*
X38382Y-48355D02*
X44842D01*
X66102Y-53355D02*
X72795D01*
X66102Y-43355D02*
X77067D01*
Y-40157D01*
X85827Y-16929D02*
X90158D01*
X85853Y-13780D02*
X90158D01*
X110958Y-20079D02*
X115251D01*
X116826Y-21654D01*
X116929D01*
X110958Y-16929D02*
X118898D01*
X383083Y-134252D02*
Y-128504D01*
X294783Y-192224D02*
X295669Y-191339D01*
X294783Y-194095D02*
Y-192224D01*
X338386Y-242913D02*
X341274D01*
X337992Y-235827D02*
X340786D01*
X390896Y-249065D02*
X390945Y-249114D01*
X387894Y-245965D02*
Y-241437D01*
X386614Y-249114D02*
X386615Y-249113D01*
X385335Y-247736D02*
X386614Y-249016D01*
X385335Y-247736D02*
Y-241437D01*
X396654Y-219291D02*
X400000D01*
X391099Y-221303D02*
X393110Y-219291D01*
X385335Y-222731D02*
X386763Y-221303D01*
X385335Y-227067D02*
Y-222731D01*
X386763Y-221303D02*
X391099D01*
X393799Y-235531D02*
X398472D01*
X382677Y-242421D02*
X382776Y-242323D01*
X382677Y-246260D02*
Y-242421D01*
X382776Y-242323D02*
Y-241437D01*
X370669Y-241339D02*
Y-236614D01*
X367654D02*
X370669D01*
X373093Y-232972D02*
X379429D01*
X368232Y-217717D02*
X371555D01*
X386319D02*
X390158D01*
X415623Y-358391D02*
X419531D01*
X414772Y-353273D02*
X419531D01*
X460678Y-359179D02*
X464315D01*
X460900Y-354061D02*
X464315D01*
X499525Y-358855D02*
X502736D01*
X499302Y-353737D02*
X502736D01*
X543698Y-358659D02*
X547717D01*
X543718Y-353540D02*
X547717D01*
X605512Y-261024D02*
X608661D01*
X605512Y-256693D02*
X608612D01*
X619858Y-250000D02*
X622101D01*
X617976Y-248118D02*
Y-246641D01*
Y-248118D02*
X619858Y-250000D01*
X617913Y-246579D02*
X617976Y-246641D01*
X615256Y-241006D02*
X622803D01*
X616006Y-302756D02*
X619148D01*
X593307Y-292126D02*
X596063D01*
X599307Y-300000D02*
X600000Y-299307D01*
Y-292126D01*
Y-288976D01*
X603839Y-285138D01*
X609547D01*
X619685Y-267323D02*
X620079Y-267717D01*
Y-275492D02*
Y-267717D01*
Y-292126D02*
Y-284547D01*
X622047Y-313307D02*
X622221Y-313481D01*
X622047Y-353307D02*
X622753D01*
X622047Y-333307D02*
X622677D01*
X622047Y-343307D02*
X623228D01*
X597795Y-353307D02*
X602559D01*
X598110Y-313307D02*
X602559D01*
X203851Y-248906D02*
X204077Y-248680D01*
X203689Y-248906D02*
X203851D01*
X204077Y-248680D02*
X209193D01*
X204099Y-242913D02*
X204333Y-242680D01*
X209193D01*
X203937Y-242913D02*
X204099D01*
X352067Y-319382D02*
Y-315599D01*
X352461Y-315204D01*
Y-315042D01*
X352106Y-337785D02*
Y-332482D01*
X352322Y-332266D01*
X-23622Y-187992D02*
X-23524Y-187894D01*
X-18504D02*
X-18406Y-187795D01*
X-23524Y-187894D02*
X-18504D01*
X6141Y-340748D02*
X9547D01*
X1181D02*
X6141D01*
Y-338779D01*
X9547D01*
X1181Y-340945D02*
Y-340748D01*
X12598Y-350000D02*
X18799D01*
X12598D02*
Y-349213D01*
X22146Y-350000D02*
X26772D01*
Y-348819D01*
X21949Y-344685D02*
X23031D01*
X26657Y-348704D02*
Y-348310D01*
X23031Y-344685D02*
X26657Y-348310D01*
Y-348704D02*
X26772Y-348819D01*
X-1181Y-352831D02*
Y-349311D01*
X8526Y-349213D02*
Y-344685D01*
Y-349213D02*
X12598D01*
X8526Y-344685D02*
X9547D01*
X-10630Y-178347D02*
X-10468D01*
X-10271Y-178543D01*
X-4724D01*
X-23507Y-241027D02*
X-18881D01*
X-23622Y-241142D02*
X-23507Y-241027D01*
X-18881D02*
X-18406Y-240551D01*
X-23524Y-294193D02*
X-18504D01*
X-18406Y-294094D01*
X-23622Y-294291D02*
X-23524Y-294193D01*
X-18504Y-114075D02*
X-18406Y-113976D01*
D19*
X596415Y-275548D02*
X596457Y-275590D01*
X596415Y-266846D02*
X596865Y-266396D01*
X601565Y-280699D02*
X606998D01*
X596457Y-275590D02*
X601565Y-280699D01*
X607677Y-280020D02*
X609547D01*
X606998Y-280699D02*
X607677Y-280020D01*
X596415Y-275548D02*
Y-266846D01*
X595215Y-276045D02*
Y-266846D01*
X594765Y-266396D02*
X595215Y-266846D01*
Y-276045D02*
X601068Y-281899D01*
X606998D01*
X607677Y-282579D02*
X609547D01*
X606998Y-281899D02*
X607677Y-282579D01*
X599906Y-242131D02*
X600689Y-242913D01*
X599906Y-242131D02*
Y-241896D01*
X599555Y-241545D02*
X599906Y-241896D01*
X599555Y-240345D02*
X599906Y-239993D01*
Y-239759D02*
X600689Y-238976D01*
X596784Y-240345D02*
X599555D01*
X599906Y-239993D02*
Y-239759D01*
X596784Y-241545D02*
X599555D01*
D25*
X225394Y-368665D02*
G03*
X225327Y-368504I-228J0D01*
G01*
X131668Y-353143D02*
G03*
X131790Y-353367I754J267D01*
G01*
X132436Y-354181D02*
G03*
X132807Y-354404I635J638D01*
G01*
X132433Y-354179D02*
G03*
X132436Y-354181I638J635D01*
G01*
X132349Y-354080D02*
G03*
X132433Y-354179I722J537D01*
G01*
X132909Y-354443D02*
G03*
X132807Y-354404I-340J-724D01*
G01*
X132915Y-354446D02*
G03*
X132909Y-354443I-347J-721D01*
G01*
X132915Y-354446D02*
G03*
X134122Y-354724I1207J2482D01*
G01*
X132349Y-354080D02*
G03*
X132337Y-354066I-639J-482D01*
G01*
X427843Y-166966D02*
Y-159646D01*
X614370Y-249489D02*
Y-246579D01*
Y-249489D02*
X614822Y-249942D01*
Y-250158D02*
Y-249942D01*
X609498Y-274852D02*
X609547Y-274902D01*
X604774Y-274852D02*
X609498D01*
X604724Y-274803D02*
X604774Y-274852D01*
X388083Y-162205D02*
Y-155512D01*
X314675Y-171238D02*
X315251Y-170662D01*
Y-170373D01*
X314675Y-173797D02*
Y-171238D01*
X315778Y-169846D02*
X317556D01*
X315251Y-170373D02*
X315778Y-169846D01*
X317556D02*
X321260Y-166142D01*
X319188Y-170662D02*
Y-170373D01*
X319715Y-169846D02*
X320311D01*
X319188Y-170373D02*
X319715Y-169846D01*
X320311D02*
X323622Y-166535D01*
X318612Y-171238D02*
X319188Y-170662D01*
X318612Y-173797D02*
Y-171238D01*
X150394Y-140157D02*
X150547Y-140004D01*
X151412D01*
X154184Y-137233D01*
X298031Y-135512D02*
Y-134468D01*
X317323Y-115177D01*
Y-114961D01*
X317717Y-111417D02*
X321260Y-114961D01*
X298031Y-125512D02*
X312126Y-111417D01*
X317717D01*
X320580Y-189741D02*
X320671Y-189650D01*
Y-183942D01*
X320761Y-183851D01*
X311495Y-211811D02*
X313857Y-209449D01*
X309449Y-211811D02*
X311495D01*
X313857Y-209449D02*
X324016D01*
X370866Y-256299D01*
X405248D01*
X411587Y-244750D02*
X412405D01*
X412873Y-245218D01*
Y-248674D02*
Y-245218D01*
X405248Y-256299D02*
X412873Y-248674D01*
X405413Y-238189D02*
X405512D01*
X406293Y-238970D01*
Y-239456D02*
Y-238970D01*
Y-239456D02*
X411587Y-244750D01*
X322311Y-211288D02*
X368701Y-257677D01*
X313386Y-212598D02*
X314696Y-211288D01*
X322311D01*
X289370Y-200394D02*
X292259D01*
X322285Y-219421D02*
X329904Y-227040D01*
X292259Y-209582D02*
Y-200394D01*
X302098Y-219421D02*
X322285D01*
X292259Y-209582D02*
X302098Y-219421D01*
X368701Y-257677D02*
X405709D01*
X408268Y-229528D02*
X413705D01*
X414173Y-229996D01*
Y-249213D02*
Y-229996D01*
X405709Y-257677D02*
X414173Y-249213D01*
X405807Y-233071D02*
X405905D01*
X406687Y-232290D01*
Y-231109D01*
X408268Y-229528D01*
X343307Y-244946D02*
Y-235039D01*
X416799Y-242792D02*
X420463D01*
X339764Y-255906D02*
Y-248489D01*
X343307Y-244946D01*
X339764Y-255906D02*
X343307Y-259449D01*
X407087D01*
X416799Y-249736D02*
Y-242792D01*
X407087Y-259449D02*
X416799Y-249736D01*
X407561Y-261024D02*
X425671Y-242913D01*
X324009Y-258262D02*
X338493D01*
X341255Y-261024D02*
X407561D01*
X338493Y-258262D02*
X341255Y-261024D01*
X320472Y-254724D02*
X324009Y-258262D01*
X337402Y-260630D02*
X339635Y-262864D01*
X413121D02*
X429134Y-246850D01*
X339635Y-262864D02*
X413121D01*
X298031Y-155669D02*
Y-155512D01*
Y-161024D02*
Y-155669D01*
X231663Y-96850D02*
X240271D01*
X216250Y-92520D02*
X227333D01*
X207195Y-101575D02*
X216250Y-92520D01*
X227333D02*
X231663Y-96850D01*
X204193Y-107421D02*
X210433Y-101181D01*
X241732Y-127295D02*
Y-101650D01*
X210433Y-101181D02*
X241264D01*
X241732Y-101650D01*
X169377Y-123622D02*
X176217D01*
X169377Y-121653D02*
X177792D01*
X79076Y-137936D02*
Y-132963D01*
X94135Y-127746D02*
X100729D01*
Y-127872D02*
Y-127746D01*
X-23622Y-181102D02*
X-23469Y-180949D01*
X-20122D02*
X-19685Y-180512D01*
X-23469Y-180949D02*
X-20122D01*
X86950Y-137936D02*
Y-132963D01*
X94135Y-125778D02*
X98761D01*
X94135Y-117904D02*
X98761D01*
X94135Y-121841D02*
X98761D01*
X94135Y-119872D02*
X100729D01*
X90887Y-114655D02*
Y-110061D01*
X86950Y-114655D02*
Y-110029D01*
X86981D01*
X90887Y-110061D02*
X91044D01*
X88918Y-114655D02*
X88981D01*
Y-108061D01*
X90887Y-137936D02*
Y-132963D01*
Y-137936D02*
X91044D01*
X98761Y-129872D02*
Y-129715D01*
X94135D02*
X98761D01*
X83013Y-137936D02*
X83044D01*
X89044Y-139557D02*
Y-132963D01*
X86950Y-137936D02*
X87044D01*
X88918Y-132963D02*
X89044D01*
X69824Y-119872D02*
Y-111604D01*
X83013Y-137936D02*
Y-132963D01*
X79044Y-137936D02*
X79076D01*
X81044Y-139557D02*
Y-132963D01*
X50926Y-115541D02*
Y-111604D01*
X69824Y-119872D02*
X75828D01*
X57422Y-120856D02*
X64312D01*
X68889Y-127746D02*
X75828D01*
X64312Y-121841D02*
Y-120856D01*
Y-121841D02*
X75828D01*
X67462Y-125778D02*
X75828D01*
X78918Y-110029D02*
X79076D01*
Y-114655D02*
Y-110029D01*
X80981Y-114655D02*
Y-108061D01*
Y-114655D02*
X81044D01*
X82918D02*
X83013D01*
X82918D02*
Y-110029D01*
X64312Y-133652D02*
X67462D01*
X68889Y-137453D02*
Y-127746D01*
X71202Y-138095D02*
Y-129715D01*
X67462Y-133652D02*
Y-125778D01*
X57422Y-120856D02*
Y-119872D01*
X52501D02*
X57422D01*
X50926Y-111604D02*
X69824D01*
X71202Y-129715D02*
X75828D01*
X44621Y-110628D02*
X44838D01*
X50926Y-111604D02*
X50926D01*
X44838Y-110628D02*
X45691Y-111481D01*
X47653D01*
X47777Y-111604D01*
Y-108061D01*
X98761Y-117904D02*
Y-117746D01*
Y-125872D02*
Y-125778D01*
Y-121871D02*
Y-121841D01*
X241732Y-127295D02*
X245683Y-131246D01*
X267541Y-171872D02*
X286439D01*
X243426Y-123411D02*
Y-100005D01*
X240271Y-96850D02*
X243426Y-100005D01*
Y-123411D02*
X248031Y-128016D01*
Y-152362D02*
Y-128016D01*
Y-152362D02*
X267541Y-171872D01*
X199134Y-368504D02*
X225327D01*
X225394Y-384891D02*
Y-368665D01*
X196701Y-370523D02*
X198682Y-368542D01*
X199096D01*
X199134Y-368504D01*
X225503Y-366842D02*
X227165Y-368504D01*
X276969Y-399280D02*
Y-368973D01*
X227165Y-368504D02*
X276500D01*
X276969Y-368973D01*
X521654Y-198819D02*
X529015Y-191457D01*
Y-190670D01*
X543853Y-175832D01*
X594995Y-186107D02*
X600000D01*
X591339Y-189764D02*
X594995Y-186107D01*
X269829Y-347494D02*
X288583Y-328740D01*
X236152Y-347494D02*
X269829D01*
X229269Y-354377D02*
X236152Y-347494D01*
X203890Y-354377D02*
X229269D01*
X391541Y-224282D02*
X404359D01*
X391541D02*
X391541Y-224282D01*
X390643Y-225180D02*
X391541Y-224282D01*
X381595Y-321933D02*
Y-315042D01*
X369784Y-321933D02*
Y-315652D01*
X375689Y-321933D02*
Y-316046D01*
X357973Y-321933D02*
Y-315042D01*
X363878Y-321933D02*
Y-315653D01*
X381595Y-337877D02*
Y-332581D01*
X332382Y-321933D02*
Y-315042D01*
X342225Y-321933D02*
Y-315691D01*
X322540Y-321933D02*
Y-315042D01*
Y-337877D02*
Y-332975D01*
X342225Y-337877D02*
Y-333369D01*
X332382Y-337877D02*
Y-332975D01*
X5584Y-237795D02*
X8403D01*
X147096Y-65354D02*
X152756D01*
X147047Y-65403D02*
X147096Y-65354D01*
Y-57480D02*
X152756D01*
X147047Y-57529D02*
X147096Y-57480D01*
X269054Y-289781D02*
X282695D01*
X284646Y-291732D01*
X381890Y-183858D02*
X385541Y-180207D01*
Y-173797D01*
X384646Y-184252D02*
X384799Y-184099D01*
X386481D02*
X387509Y-183071D01*
X384799Y-184099D02*
X386481D01*
X544882Y-311417D02*
Y-305118D01*
X383083Y-161839D02*
Y-155512D01*
X390453Y-244783D02*
X392126Y-246457D01*
X390453Y-244783D02*
Y-241437D01*
X394193Y-246457D02*
X395971Y-248235D01*
X392126Y-246457D02*
X394193D01*
X396069Y-248235D02*
X396850Y-249016D01*
X395971Y-248235D02*
X396069D01*
X129063Y-136618D02*
X130540Y-135141D01*
Y-132385D01*
X38613Y-53355D02*
X44842D01*
X169377Y-135433D02*
X169623D01*
X172575Y-138386D02*
X172674D01*
X169623Y-135433D02*
X172575Y-138386D01*
X613406Y-89494D02*
Y-83465D01*
X388083Y-162205D02*
X388189D01*
X394848Y-239881D02*
Y-238281D01*
Y-239881D02*
X401575Y-246607D01*
X393799Y-238090D02*
X394658D01*
X394848Y-238281D01*
X401575Y-249213D02*
Y-249114D01*
Y-246607D01*
X126307Y-136224D02*
X127981Y-134551D01*
Y-132385D01*
X38583Y-58355D02*
X44842D01*
X166178Y-135679D02*
X166270Y-135771D01*
Y-137494D02*
Y-135771D01*
Y-137494D02*
X167949Y-139173D01*
X169524D01*
X170311Y-139961D01*
X553543Y-262402D02*
Y-246463D01*
X550391Y-243310D02*
X553543Y-246463D01*
X515327Y-209842D02*
X525591D01*
X534646Y-200787D01*
Y-198031D01*
X531890Y-195276D02*
X534646Y-198031D01*
X531890Y-195276D02*
Y-191732D01*
X544763Y-178859D01*
X574922D01*
X585558Y-189495D01*
X585132Y-206465D02*
Y-199550D01*
X585558Y-199124D01*
Y-189495D01*
X589370Y-212992D02*
Y-210702D01*
X585132Y-206465D02*
X589370Y-210702D01*
X588922Y-206353D02*
X595036D01*
X514404Y-206462D02*
X526686D01*
X533071Y-200077D02*
Y-198819D01*
X526686Y-206462D02*
X533071Y-200077D01*
X530315Y-196063D02*
X533071Y-198819D01*
X530315Y-196063D02*
Y-191339D01*
X544095Y-177559D01*
X575984D01*
X587402Y-188976D01*
Y-202953D02*
Y-188976D01*
X588910Y-206450D02*
Y-204462D01*
Y-206450D02*
X588922Y-206462D01*
X587402Y-202953D02*
X588910Y-204462D01*
X543853Y-175832D02*
X577210D01*
X589370Y-187992D01*
Y-201575D02*
Y-187992D01*
X483831Y-241339D02*
X515327Y-209842D01*
X288Y-234646D02*
X3445D01*
X154184Y-135426D02*
X155856Y-133754D01*
X156784D01*
X154184Y-137233D02*
Y-135426D01*
X156784Y-133754D02*
X157073Y-133465D01*
X393947Y-232825D02*
X402116D01*
X393799Y-232972D02*
X393947Y-232825D01*
X402116Y-234990D02*
X405340Y-238214D01*
X402116Y-234990D02*
Y-232825D01*
X405340Y-238263D02*
Y-238214D01*
Y-238263D02*
X405413Y-238189D01*
X393799Y-230413D02*
X403051D01*
X405709Y-233071D01*
X405807D01*
X135658Y-124314D02*
X140116D01*
X282358Y-181316D02*
X292734D01*
X299606Y-188189D02*
X301575D01*
X292734Y-181316D02*
X299606Y-188189D01*
X298031Y-161024D02*
X302256Y-165248D01*
Y-187508D02*
Y-165248D01*
X301575Y-188189D02*
X302256Y-187508D01*
X281890Y-181785D02*
X282358Y-181316D01*
X281890Y-188583D02*
Y-181785D01*
X286439Y-171872D02*
X299606Y-185039D01*
X364173Y-290035D02*
Y-280315D01*
X351058Y-303150D02*
X364173Y-290035D01*
X341535Y-303150D02*
X351058D01*
X423885Y-239370D02*
X434252D01*
X420463Y-242792D02*
X423885Y-239370D01*
X466535Y-238189D02*
X488189Y-216535D01*
X466535Y-279528D02*
Y-238189D01*
X461088Y-284975D02*
X466535Y-279528D01*
X468627Y-240517D02*
X509931Y-199213D01*
X468158Y-283071D02*
X468627Y-282602D01*
X465382Y-283071D02*
X468158D01*
X468627Y-282602D02*
Y-240517D01*
X456545Y-258295D02*
X462205D01*
Y-255118D01*
X461088Y-294318D02*
Y-284975D01*
X454605Y-300801D02*
X461088Y-294318D01*
X454605Y-304529D02*
Y-300801D01*
X454017Y-305118D02*
X454605Y-304529D01*
X434252Y-305118D02*
X454017D01*
X430040Y-300906D02*
X434252Y-305118D01*
X430040Y-300906D02*
Y-276847D01*
X430509Y-276378D01*
X434252D01*
Y-239370D01*
X455905Y-302756D02*
X457426Y-301235D01*
Y-300578D02*
X462473Y-295531D01*
X455905Y-305118D02*
Y-302756D01*
X462473Y-295531D02*
Y-285980D01*
X457426Y-301235D02*
Y-300578D01*
X335308Y-227040D02*
X343307Y-235039D01*
X329904Y-227040D02*
X335308D01*
X467708Y-81102D02*
Y-76378D01*
X451575Y-81102D02*
X467708D01*
X451575D02*
Y-76378D01*
X404187Y-211561D02*
X425840D01*
X435433Y-201969D02*
Y-199334D01*
X425840Y-211561D02*
X435433Y-201969D01*
X427953Y-206299D02*
Y-206216D01*
X432040Y-202128D01*
Y-201048D01*
X481496Y-219614D02*
Y-197244D01*
X464469Y-236641D02*
X481496Y-219614D01*
X177657Y-92126D02*
Y-87795D01*
X168947Y13041D02*
X169291Y13386D01*
X611811Y-221332D02*
Y-221260D01*
X610433Y-222710D02*
X611811Y-221332D01*
X610433Y-228740D02*
Y-222710D01*
X389478Y-196440D02*
Y-189741D01*
X433971Y-189726D02*
X434936Y-188760D01*
X431890Y-183465D02*
X434936Y-186511D01*
Y-188760D02*
Y-186511D01*
X322549Y-196063D02*
Y-189741D01*
X244410Y-248458D02*
X253110D01*
X245965Y-250411D02*
X253110D01*
X243996Y-252379D02*
X253110D01*
X245965Y-254348D02*
X253110D01*
X244028Y-258285D02*
X253110D01*
X245965Y-260253D02*
X253110D01*
X244028Y-262222D02*
X253110D01*
X245965Y-264190D02*
X253110D01*
X432720Y-289791D02*
X440601D01*
X432835Y-291759D02*
X440601D01*
X-8465Y-316929D02*
X13874D01*
X12306Y-315361D02*
X13874Y-316929D01*
X9843Y-312799D02*
X12306Y-315262D01*
X13874Y-316929D02*
X13973D01*
X12306Y-315361D02*
Y-315262D01*
X9843Y-312799D02*
Y-303150D01*
X2756Y-296063D02*
X9843Y-303150D01*
X2756Y-296063D02*
Y-291732D01*
X21949Y-342717D02*
X27045D01*
X29543Y-345214D01*
X269054Y-274033D02*
X280382D01*
X19685Y-2362D02*
X20079Y-1969D01*
X25787D01*
X20079Y3937D02*
X21063Y4921D01*
X25787D01*
X20079Y10630D02*
X21260Y11811D01*
X25787D01*
X20079Y17323D02*
X21457Y18701D01*
X25787D01*
X-8465Y-210630D02*
X13973D01*
X3999Y-192200D02*
Y-188447D01*
X2756Y-187205D02*
X3999Y-188447D01*
Y-192200D02*
X7471Y-195672D01*
Y-198805D02*
Y-195672D01*
Y-198805D02*
X13973Y-205307D01*
Y-210630D02*
Y-205307D01*
X326486Y-179059D02*
Y-173797D01*
X288583Y-310236D02*
Y-282477D01*
Y-328740D02*
Y-310236D01*
X391339Y-277953D02*
X404724D01*
X405905Y-279134D01*
Y-288189D02*
Y-279134D01*
X383858Y-310236D02*
X405905Y-288189D01*
X288583Y-310236D02*
X383858D01*
X280382Y-274277D02*
X288583Y-282477D01*
X190354Y-367913D02*
X203890Y-354377D01*
X190354Y-377411D02*
Y-367913D01*
X299606Y-185433D02*
Y-185039D01*
X204331Y-101575D02*
X207195D01*
X224941Y-238680D02*
X229802D01*
X230886Y-239764D01*
X231102D01*
X203150Y-102756D02*
X204331Y-101575D01*
X200295Y-102756D02*
X203150D01*
X513406Y-311417D02*
Y-302902D01*
X456545Y-236641D02*
X464469D01*
X242478Y-140945D02*
X243426Y-141893D01*
Y-182796D02*
X261024Y-200394D01*
X243426Y-182796D02*
Y-141893D01*
X234921Y-140945D02*
X242478D01*
X233209Y-139232D02*
X234921Y-140945D01*
X269783Y-199488D02*
X277677Y-207382D01*
X279528D01*
X245683Y-181509D02*
Y-131246D01*
Y-181509D02*
X260630Y-196457D01*
X269783D01*
Y-199488D02*
Y-196457D01*
X456545Y-248452D02*
X463453D01*
X507283Y-298130D02*
Y-292126D01*
X269054Y-283875D02*
X280414D01*
X269054Y-287812D02*
X280414D01*
X318989Y-253024D02*
X320294Y-254330D01*
X320472D01*
Y-254724D02*
Y-254330D01*
X425671Y-242913D02*
X431496D01*
X432863Y-244281D01*
Y-249694D02*
Y-244281D01*
X428740Y-253817D02*
X432863Y-249694D01*
X428740Y-301575D02*
Y-253817D01*
Y-301575D02*
X434252Y-307087D01*
X453937D01*
X455905Y-305118D01*
X463779Y-296063D02*
Y-293187D01*
X458726Y-301116D02*
X463779Y-296063D01*
Y-293187D02*
X471140Y-285827D01*
X482677D01*
X462473Y-285980D02*
X465382Y-283071D01*
X509931Y-199213D02*
X513386D01*
X500971Y-219896D02*
X514404Y-206462D01*
X470472Y-246457D02*
Y-246063D01*
X542520Y-174016D01*
X581890D01*
X451575Y-76378D02*
X452551Y-75402D01*
X288091Y-207185D02*
X289370Y-205906D01*
X283858Y-207185D02*
X288091D01*
X246162Y-293718D02*
X253110D01*
X269054D02*
X280414D01*
X342805Y-212490D02*
X355404D01*
X340589Y-206569D02*
X348139Y-199019D01*
X340589Y-210275D02*
Y-206569D01*
Y-210275D02*
X342805Y-212490D01*
X355404D02*
X357480Y-214567D01*
X348139Y-199019D02*
Y-189741D01*
X343701Y-200394D02*
X346171Y-197924D01*
Y-189741D01*
X168110Y-10433D02*
X174114D01*
X164715Y13041D02*
X168947D01*
X164567Y12894D02*
X164715Y13041D01*
X159990D02*
X164419D01*
X159843Y13189D02*
X159990Y13041D01*
X164419D02*
X164567Y12894D01*
X552756Y-311417D02*
Y-305118D01*
X505410Y-336036D02*
Y-328917D01*
X513386Y-336221D02*
Y-328917D01*
X337598Y-281102D02*
Y-276969D01*
X339204Y-275363D01*
X341916D01*
X343325Y-276772D01*
X383071D01*
X337992Y-306937D02*
Y-303150D01*
X376922Y-306937D02*
X402756Y-281102D01*
X337992Y-306937D02*
X376922D01*
X418171Y-331950D02*
X437008Y-350787D01*
X316929Y-273622D02*
X413386D01*
X418171Y-331950D02*
Y-278407D01*
X413386Y-273622D02*
X418171Y-278407D01*
X420779Y-331015D02*
X439764Y-350000D01*
X317872Y-270079D02*
X412598D01*
X420779Y-331015D02*
Y-278259D01*
X412598Y-270079D02*
X420779Y-278259D01*
X422720Y-330594D02*
X440158Y-348031D01*
X317742Y-268110D02*
X414961D01*
X422720Y-330594D02*
Y-275870D01*
X414961Y-268110D02*
X422720Y-275870D01*
X424787Y-327150D02*
X443307Y-345669D01*
X318973Y-264961D02*
X415354D01*
X424787Y-327150D02*
Y-274394D01*
X415354Y-264961D02*
X424787Y-274394D01*
X333366Y-302854D02*
X337697D01*
X333071Y-302559D02*
X333366Y-302854D01*
X337697D02*
X337992Y-303150D01*
X328839Y-302461D02*
X332972D01*
X328740Y-302362D02*
X328839Y-302461D01*
X332972D02*
X333071Y-302559D01*
X616929Y-231319D02*
Y-226378D01*
X616929Y-226378D02*
Y-225984D01*
Y-226378D02*
X616929Y-226378D01*
X595860Y-148825D02*
Y-147644D01*
X599016Y-144488D01*
X594685Y-150000D02*
X595860Y-148825D01*
X591339Y-144488D02*
X595472D01*
X582165Y-163898D02*
X590530D01*
X581890Y-174016D02*
X582008Y-173898D01*
X590530D01*
X589370Y-212992D02*
X591009Y-211353D01*
X595036D01*
X588922Y-206462D02*
Y-206353D01*
X589370Y-201575D02*
X589592Y-201353D01*
X595036D01*
X247146Y-218915D02*
X253110D01*
X520079Y-355036D02*
X520866Y-354249D01*
X245064Y-216784D02*
Y-207348D01*
Y-216784D02*
X247146Y-218866D01*
X245064Y-207348D02*
X249263Y-203150D01*
X267717D01*
X273833Y-209266D01*
X278557D01*
X304450Y-235158D01*
Y-250438D02*
Y-235158D01*
Y-250438D02*
X318973Y-264961D01*
X443307Y-345669D02*
X516535D01*
X520866Y-350000D01*
Y-354249D02*
Y-350000D01*
X520079Y-355036D02*
X521339Y-356296D01*
X247144Y-216946D02*
X253110D01*
X247144Y-210336D02*
X251575Y-205906D01*
X247144Y-216946D02*
Y-210336D01*
X251575Y-205906D02*
X265159D01*
X274608Y-215354D01*
X281019D01*
X303150Y-253518D02*
Y-237485D01*
X281019Y-215354D02*
X303150Y-237485D01*
Y-253518D02*
X317742Y-268110D01*
X440158Y-348031D02*
X489764D01*
X495276Y-353543D01*
Y-359789D02*
Y-353543D01*
Y-359789D02*
X496227Y-360740D01*
X559984D01*
X561579Y-359144D01*
X564357D02*
X565827Y-357674D01*
Y-356690D01*
X561579Y-359144D02*
X564357D01*
X511594Y-356296D02*
X521339D01*
X561547Y-356099D02*
X562137Y-356690D01*
X565827D01*
X561330Y-356099D02*
X561547D01*
X556575D02*
X561330D01*
X485699Y-344222D02*
X499339Y-330582D01*
X467742Y-343333D02*
X468632Y-344222D01*
X485699D01*
X269054Y-216946D02*
X280773D01*
X301342Y-237515D01*
Y-253549D02*
Y-237515D01*
Y-253549D02*
X317872Y-270079D01*
X439764Y-350000D02*
X470472D01*
X472780Y-352307D02*
X481441D01*
X470472Y-350000D02*
X472780Y-352307D01*
X299213Y-255906D02*
Y-239388D01*
X278740Y-218915D02*
X299213Y-239388D01*
Y-255906D02*
X316929Y-273622D01*
X436953Y-350842D02*
X437008Y-350787D01*
X436953Y-355832D02*
Y-350842D01*
X481441Y-356620D02*
Y-352307D01*
X328454Y-189741D02*
Y-184678D01*
Y-180600D02*
Y-173797D01*
X329528Y-181890D02*
Y-181673D01*
X328454Y-180600D02*
X329528Y-181673D01*
X309842Y-201575D02*
X328928D01*
X307087Y-198819D02*
X309842Y-201575D01*
X328928D02*
X334360Y-196142D01*
Y-189741D01*
X278309Y-258285D02*
X284646Y-251949D01*
Y-237799D01*
X269054Y-258285D02*
X278309D01*
X279161Y-232315D02*
X284646Y-237799D01*
X279134Y-230315D02*
X279161Y-230342D01*
Y-232315D02*
Y-230342D01*
X280315Y-226378D02*
X286614Y-232677D01*
Y-252756D02*
Y-232677D01*
X269054Y-260253D02*
X279117D01*
X286614Y-252756D01*
X6791Y-234646D02*
X10007D01*
X276625Y-252379D02*
X279134Y-249871D01*
X277165Y-236437D02*
X279134Y-238405D01*
Y-249871D02*
Y-238405D01*
X277165Y-236437D02*
Y-236221D01*
X269054Y-252379D02*
X276625D01*
X269054Y-254348D02*
X279178D01*
X281496Y-252030D02*
Y-237402D01*
X279178Y-254348D02*
X281496Y-252030D01*
X21949Y-340748D02*
X22139Y-340558D01*
X24403D02*
X27559Y-337402D01*
X22139Y-340558D02*
X24403D01*
X279429Y-262222D02*
X289764Y-251888D01*
X288583Y-237402D02*
X289764Y-238583D01*
Y-251888D02*
Y-238583D01*
X293307Y-253543D02*
Y-237008D01*
X282660Y-264190D02*
X293307Y-253543D01*
X269054Y-264190D02*
X282660D01*
X9843Y-185236D02*
X14665D01*
X27067D02*
X33071D01*
X341142Y-278150D02*
X341339Y-277953D01*
X341142Y-281102D02*
Y-278150D01*
X402010Y-219685D02*
X404626D01*
X404626Y-219685D01*
X462473Y-277635D02*
X462859D01*
X461417Y-305118D02*
X461516Y-305020D01*
X472548D01*
X461417Y-308465D02*
Y-305118D01*
X472548Y-305020D02*
X472647Y-304921D01*
X343701Y-209449D02*
X357982Y-195168D01*
Y-189741D01*
X347638Y-202756D02*
X347827D01*
X354045Y-196538D01*
Y-189741D01*
X383071Y-168327D02*
X383572Y-168828D01*
Y-173797D02*
Y-168828D01*
X383071Y-168327D02*
Y-168110D01*
X402290Y-213458D02*
X404187Y-211561D01*
X383244Y-215354D02*
X385141Y-213458D01*
X402290D01*
X375000Y-217717D02*
X380906Y-211811D01*
X400394D01*
X419552Y-192653D01*
X382972Y-217717D02*
X383244Y-217445D01*
X382776Y-217913D02*
X382972Y-217717D01*
X432040Y-191656D02*
X433971Y-189726D01*
X383244Y-217445D02*
Y-215354D01*
X433971Y-197872D02*
X435433Y-199334D01*
X433971Y-197872D02*
Y-189726D01*
X419552Y-192653D02*
X424560D01*
X394306Y-209449D02*
X415566Y-188189D01*
X377334Y-209449D02*
X394306D01*
X371761Y-203876D02*
X377334Y-209449D01*
X371761Y-203876D02*
Y-189741D01*
X417717Y-183465D02*
X431890D01*
X393277Y-207905D02*
X417717Y-183465D01*
X381133Y-207905D02*
X393277D01*
X377667Y-204439D02*
X381133Y-207905D01*
X377667Y-204439D02*
Y-189741D01*
X424409Y-205512D02*
X424560Y-205361D01*
Y-201048D01*
X432040Y-192653D02*
Y-191656D01*
X415566Y-188189D02*
X421093D01*
X424560Y-191656D01*
Y-192653D02*
Y-191656D01*
X140116Y-124314D02*
Y-124048D01*
X203839Y-15354D02*
X211811D01*
X142287Y1378D02*
X145087D01*
X141339Y394D02*
Y429D01*
X142287Y1378D01*
X149803Y12992D02*
X151083Y14272D01*
X157687Y-4735D02*
X162500Y-9547D01*
X201476Y-91732D02*
Y-87795D01*
X200295Y-100886D02*
X201476Y-99705D01*
Y-91732D01*
X200295Y-102756D02*
Y-100886D01*
X194882Y-102756D02*
X197244D01*
X197343D01*
X177559Y-87795D02*
X177657D01*
X177854Y-100984D02*
Y-92323D01*
Y-100984D02*
X178051Y-101181D01*
X177657Y-92126D02*
X177854Y-92323D01*
X187008Y-87795D02*
X188189Y-88976D01*
Y-91929D02*
Y-88976D01*
X180610Y-87795D02*
X187008D01*
X186608Y-92028D02*
X186614Y-92021D01*
X180610Y-92126D02*
X180709Y-92028D01*
X186614Y-92021D02*
Y-91929D01*
X180709Y-92028D02*
X186608D01*
X191345Y-90151D02*
X193701Y-87795D01*
X198524D01*
X191345Y-91923D02*
Y-90151D01*
X191339Y-91929D02*
X191345Y-91923D01*
X192913Y-91837D02*
X192920Y-91831D01*
X198425D02*
X198524Y-91732D01*
X192913Y-91929D02*
Y-91837D01*
X192920Y-91831D02*
X198425D01*
X192920Y-97638D02*
X197638D01*
X192913Y-97632D02*
X192920Y-97638D01*
X192913Y-97632D02*
Y-97047D01*
X191339Y-99213D02*
X194882Y-102756D01*
X191339Y-99213D02*
Y-97047D01*
X181004Y-101181D02*
X185328D01*
X188183Y-98326D02*
Y-97053D01*
X188189Y-97047D01*
X185328Y-101181D02*
X188183Y-98326D01*
X182283Y-97244D02*
X183268Y-96260D01*
X186614D01*
X182677Y-94488D02*
X186614D01*
X189764Y-100787D02*
Y-97047D01*
X192913Y-94488D02*
X196850D01*
X117323Y-65403D02*
X129547D01*
X161368Y-25934D02*
X161417Y-25984D01*
X160236Y-26403D02*
X160705Y-25934D01*
X160236Y-54331D02*
Y-26403D01*
X160705Y-25934D02*
X161368D01*
X160236Y-59055D02*
Y-54331D01*
X163386Y-44340D02*
X165797Y-41929D01*
X163386Y-54331D02*
Y-44340D01*
X165797Y-41929D02*
X174114D01*
X169291Y13189D02*
Y13386D01*
X151181Y14173D02*
Y14370D01*
X162598Y-9646D02*
Y-9449D01*
X158809Y-13041D02*
X162451D01*
X158661Y-12894D02*
X158809Y-13041D01*
X157677Y-13976D02*
X158661Y-12992D01*
X153543Y-13976D02*
X157677D01*
X158661Y-12992D02*
Y-12894D01*
X157587Y-2559D02*
X157687Y-2659D01*
X156487Y-2559D02*
X157587D01*
X157687Y-4735D02*
Y-2659D01*
X153740Y-6406D02*
X156691Y-9357D01*
X158661Y-9941D02*
Y-9843D01*
X153740Y-6406D02*
Y-5306D01*
X156691Y-9357D02*
X158176D01*
X158661Y-9843D01*
X151772Y-8661D02*
Y-5306D01*
Y-8661D02*
X153543Y-10433D01*
X161614Y-591D02*
X162598Y-1575D01*
X156487Y-591D02*
X161614D01*
X156487Y1378D02*
X161024D01*
X169291Y9646D01*
X157587Y3347D02*
X163598Y9357D01*
X164081D01*
X164567Y9843D01*
X156487Y3347D02*
X157587D01*
X164567Y9843D02*
Y9941D01*
X156291Y6094D02*
X159843Y9646D01*
X153740Y6094D02*
X156291D01*
X151181Y17913D02*
Y18110D01*
X150492Y17224D02*
X151181Y17913D01*
X146850Y17224D02*
X150492D01*
X146365Y16732D02*
X146850Y17218D01*
X142520Y16732D02*
X146365D01*
X146850Y17218D02*
Y17224D01*
X149803Y6094D02*
Y12992D01*
X146850Y14173D02*
Y14272D01*
X147835Y6094D02*
Y13189D01*
X146850Y14173D02*
X147835Y13189D01*
X142520Y4814D02*
Y13189D01*
X143987Y3347D02*
X145087D01*
X142520Y4814D02*
X143987Y3347D01*
X143207Y-691D02*
X144987D01*
X137598Y-6299D02*
X143207Y-691D01*
X144987D02*
X145087Y-591D01*
X139672Y-9843D02*
X141340Y-8174D01*
X142219D01*
X143887Y-6506D01*
X136909Y-9843D02*
X139672D01*
X143887Y-2659D02*
X143987Y-2559D01*
X145087D01*
X143887Y-6506D02*
Y-2659D01*
X134006Y-9793D02*
Y-6348D01*
X133957Y-9843D02*
X134006Y-9793D01*
X134541Y-10617D02*
X135735Y-11811D01*
X134055Y-9843D02*
X134541Y-10328D01*
X135735Y-11811D02*
X141142D01*
X134541Y-10617D02*
Y-10328D01*
X144685Y-11811D02*
X147835Y-8661D01*
Y-5306D01*
X149803Y-9238D02*
Y-5306D01*
X472835Y-276008D02*
X473303Y-276476D01*
X479921D01*
X474459Y-256988D02*
X476772D01*
X472146D02*
X474459D01*
Y-249951D02*
X477165Y-247244D01*
X474459Y-256988D02*
Y-249951D01*
X518898Y-300394D02*
X521408Y-302904D01*
Y-311417D02*
Y-302904D01*
X503543Y-300394D02*
X518898D01*
X501695Y-302242D02*
X503543Y-300394D01*
X501695Y-314896D02*
Y-302242D01*
X499339Y-317252D02*
X501695Y-314896D01*
X499339Y-330582D02*
Y-317252D01*
X467742Y-343333D02*
Y-327507D01*
X458726Y-318491D02*
X467742Y-327507D01*
X458726Y-318491D02*
Y-301116D01*
X482677Y-285827D02*
X488903Y-279601D01*
Y-277879D01*
X487500Y-276476D02*
X488903Y-277879D01*
X485827Y-276476D02*
X487500D01*
X512205Y-262402D02*
Y-254429D01*
X521654Y-336221D02*
Y-329163D01*
X521408Y-328917D02*
X521654Y-329163D01*
X552904Y-335827D02*
Y-328917D01*
X482677Y-279429D02*
X485827D01*
X479921D02*
X482677D01*
X484258Y-267329D02*
X485827Y-268898D01*
Y-276476D02*
Y-268898D01*
X482874Y-267323D02*
X482880Y-267329D01*
X484258D01*
X482776Y-276378D02*
Y-268904D01*
X482782Y-268898D02*
X482874D01*
X482776Y-268904D02*
X482782Y-268898D01*
X482677Y-276476D02*
X482776Y-276378D01*
X472835Y-276008D02*
Y-269685D01*
X475197Y-267323D01*
X477756D01*
X483071Y-254035D02*
X487402D01*
X476772D02*
X483071D01*
X485433Y-264173D02*
X487402Y-262205D01*
X482874Y-264173D02*
X485433D01*
X487402Y-262205D02*
Y-256988D01*
X483065Y-262598D02*
X483071Y-262592D01*
Y-256988D01*
X482874Y-262598D02*
X483065D01*
X471260Y-257874D02*
X472146Y-256988D01*
X471260Y-259097D02*
Y-257874D01*
Y-259097D02*
X476330Y-264167D01*
X477750D02*
X477756Y-264173D01*
X476330Y-264167D02*
X477750D01*
X473622Y-259055D02*
X474016D01*
X477559Y-262598D01*
X478543D01*
X476378Y-273622D02*
X477756Y-272244D01*
Y-268898D01*
X474409Y-265748D02*
X477756D01*
X480315Y-262598D02*
Y-259744D01*
Y-271752D02*
Y-268898D01*
X545030Y-336221D02*
Y-328917D01*
X544882Y-300787D02*
X548819D01*
X461417Y-312099D02*
Y-312008D01*
X476083Y-289075D02*
X476772Y-288386D01*
X472835Y-289075D02*
X476083D01*
X471168Y-289659D02*
X472349D01*
X472835Y-289173D02*
Y-289075D01*
X466142Y-294685D02*
X471168Y-289659D01*
X472349D02*
X472835Y-289173D01*
X461024Y-302756D02*
X461221Y-302953D01*
X472647D01*
X468898Y-300984D02*
X472647D01*
X466142Y-298228D02*
X468898Y-300984D01*
X472835Y-292126D02*
X475394Y-294685D01*
Y-298237D02*
Y-294685D01*
X472835Y-292126D02*
Y-292028D01*
X477262Y-298137D02*
Y-292420D01*
Y-298137D02*
X477362Y-298237D01*
X476772Y-291929D02*
X477262Y-292420D01*
X490945Y-298622D02*
Y-292913D01*
Y-298622D02*
X495866Y-303543D01*
X490256Y-292224D02*
X490945Y-292913D01*
X488583Y-292224D02*
X490256D01*
X487113Y-291640D02*
X488097D01*
X488583Y-292224D02*
Y-292126D01*
X483465Y-287992D02*
X487113Y-291640D01*
X488097D02*
X488583Y-292126D01*
X481299Y-293701D02*
X483465Y-291535D01*
X481299Y-298237D02*
Y-293701D01*
X485247Y-298612D02*
X488583Y-295276D01*
X484047Y-300984D02*
X485147D01*
X485247Y-300884D01*
Y-298612D01*
X488583Y-295276D02*
Y-295177D01*
X484146Y-303053D02*
X491832D01*
X484047Y-302953D02*
X484146Y-303053D01*
X489764Y-307087D02*
X498425D01*
X487598Y-304921D02*
X489764Y-307087D01*
X484047Y-304921D02*
X487598D01*
X492963Y-314026D02*
Y-310384D01*
X492815Y-314173D02*
X492963Y-314026D01*
Y-310384D02*
X493110Y-310236D01*
X490105Y-315998D02*
X491181D01*
X492231Y-314948D02*
Y-314659D01*
X492717Y-314173D02*
X492815D01*
X488386Y-317717D02*
X490105Y-315998D01*
X491181D02*
X492231Y-314948D01*
Y-314659D02*
X492717Y-314173D01*
X485147Y-306890D02*
X486378Y-308121D01*
Y-309221D02*
X487393Y-310236D01*
X484047Y-306890D02*
X485147D01*
X486378Y-309221D02*
Y-308121D01*
X487393Y-310236D02*
X489567D01*
X481299Y-310737D02*
X481399Y-310837D01*
X483671D02*
X487007Y-314173D01*
X481299Y-310737D02*
Y-309637D01*
X481399Y-310837D02*
X483671D01*
X487007Y-314173D02*
X489862D01*
X479331Y-312205D02*
X484842Y-317717D01*
X479331Y-312205D02*
Y-309637D01*
X469676Y-308760D02*
X471547Y-306890D01*
X465748Y-308760D02*
X469676D01*
X471547Y-306890D02*
X472647D01*
X461565Y-311860D02*
X465600D01*
X465748Y-311713D01*
X461417Y-312008D02*
X461565Y-311860D01*
X465748Y-311811D02*
X468609Y-314672D01*
X469593D02*
X470276Y-315354D01*
X465748Y-311811D02*
Y-311713D01*
X468609Y-314672D02*
X469593D01*
X473819Y-312312D02*
X475394Y-310737D01*
Y-309637D01*
X473819Y-315354D02*
Y-312312D01*
X551968Y-300787D02*
Y-297638D01*
X544882Y-300787D02*
X544882Y-300787D01*
X539345Y-299188D02*
X540133D01*
X541732Y-300787D01*
X538779Y-298622D02*
X539345Y-299188D01*
X538779Y-298622D02*
Y-292126D01*
X222566Y-75072D02*
Y-31228D01*
X212205Y-85433D02*
X222566Y-75072D01*
X222441Y-31102D02*
X222566Y-31228D01*
X169291Y-85433D02*
X212205D01*
X163386Y-79527D02*
X169291Y-85433D01*
X163386Y-79527D02*
Y-59055D01*
X159994Y-58813D02*
X160236Y-59055D01*
X129547Y-18159D02*
Y-14980D01*
X127165Y-12598D02*
X129547Y-14980D01*
X127743Y-51460D02*
X129547Y-49655D01*
X121870Y-52756D02*
X123166Y-51460D01*
X127743D01*
X121653Y-52756D02*
X121870D01*
X121653Y-31496D02*
X124065Y-33907D01*
X129547D01*
X404493Y-224149D02*
X404626Y-224016D01*
X404359Y-224282D02*
X404493Y-224149D01*
X507283Y-298130D02*
X507480D01*
X501181D02*
X501279Y-298031D01*
Y-292224D02*
X501378Y-292126D01*
X516929Y-298130D02*
X517126D01*
X522835Y-297736D02*
X523032D01*
X540748Y-297342D02*
X540945D01*
X546457D02*
X546654D01*
X562205Y-297736D02*
X562402D01*
X568110D02*
X568307D01*
X570276D02*
X570472D01*
X568898Y-256791D02*
X569291D01*
X551575Y-262402D02*
Y-255610D01*
X550000D02*
X551575D01*
X533858Y-262402D02*
Y-256004D01*
X540945D01*
X531890Y-262402D02*
Y-250886D01*
X538976D01*
X529921Y-262402D02*
Y-245374D01*
X536614D01*
X524016Y-262402D02*
Y-255217D01*
X518110D02*
X524016D01*
X525984Y-262402D02*
Y-249705D01*
X522047D02*
X525984D01*
X527953Y-262402D02*
Y-243799D01*
X524016D02*
X527953D01*
X504331Y-257185D02*
X504331D01*
X512205Y-254429D02*
X513386D01*
X510236Y-262402D02*
Y-251673D01*
X508268D02*
X510236D01*
X214567Y-13386D02*
Y-11417D01*
X203839Y-13386D02*
X214567D01*
X211811Y-16535D02*
Y-15354D01*
X209055Y-7480D02*
Y-7480D01*
X203839Y-31102D02*
X222441D01*
X216535Y-29134D02*
Y-25197D01*
X203839Y-29134D02*
X216535D01*
X211024Y-27165D02*
Y-21260D01*
X203839Y-27165D02*
X211024D01*
X220866Y-39764D02*
Y-33071D01*
X203839D02*
X220866D01*
X215354Y-42126D02*
Y-35039D01*
X203839D02*
X215354D01*
X210236Y-44094D02*
Y-37008D01*
X203839D02*
X210236D01*
X210630Y-54724D02*
Y-53150D01*
X203839Y-54724D02*
X210630D01*
X209541Y-58689D02*
Y-56693D01*
X203839D02*
X209541D01*
X209449Y-72441D02*
Y-72047D01*
X168504Y-73622D02*
Y-73425D01*
Y-71457D02*
Y-71260D01*
Y-65551D02*
Y-65354D01*
X168898Y-49803D02*
Y-49606D01*
Y-44094D02*
Y-43898D01*
X168504Y-37992D02*
Y-37795D01*
Y-32087D02*
Y-31890D01*
Y-26181D02*
Y-25984D01*
X168110Y-20276D02*
Y-20079D01*
X174016Y-4429D02*
X174114Y-4528D01*
X168110Y-4331D02*
X168209Y-4429D01*
X168110Y-10630D02*
Y-10433D01*
X117323Y-65403D02*
Y-65354D01*
X537156Y-340945D02*
X540551D01*
X537156D02*
Y-328917D01*
X544882Y-336221D02*
X545030D01*
X552756Y-335827D02*
X552904D01*
X552756Y-311417D02*
X552904D01*
X544882D02*
X545030D01*
X513406D02*
X513534D01*
X513386Y-328917D02*
X513534D01*
X505410D02*
X505660D01*
X618110Y-62205D02*
Y-62205D01*
X613406Y-62205D02*
X618110D01*
X238199Y-113376D02*
Y-107097D01*
Y-113376D02*
X238209Y-113386D01*
X238189Y-107087D02*
X238199Y-107097D01*
X233140Y-113317D02*
Y-107156D01*
Y-113317D02*
X233209Y-113386D01*
X233071Y-107087D02*
X233140Y-107156D01*
X223209Y-107500D02*
X223228Y-107480D01*
X223209Y-113386D02*
Y-107500D01*
X228209Y-107618D02*
X228346Y-107480D01*
X228209Y-113386D02*
Y-107618D01*
X233209Y-139232D02*
Y-132283D01*
X228209Y-138721D02*
Y-132283D01*
X223209Y-137815D02*
Y-132283D01*
X199193Y-112795D02*
Y-105925D01*
X204193Y-138257D02*
Y-131299D01*
X199193Y-138680D02*
Y-131299D01*
X130245Y-120870D02*
X130540Y-121165D01*
Y-124314D02*
Y-121165D01*
X133099Y-136519D02*
Y-132385D01*
X150627Y-130512D02*
X152595D01*
X155259Y-127848D01*
X156784D01*
X157073Y-127559D01*
X186847Y-135236D02*
Y-135236D01*
X184485Y-132874D02*
X186847Y-135236D01*
X184485Y-113583D02*
X188028D01*
X181335Y-117323D02*
Y-113583D01*
Y-117323D02*
X182516Y-118504D01*
X181335Y-132874D02*
Y-129527D01*
X182516Y-128347D01*
X188186D02*
X189209Y-127323D01*
X182516Y-128347D02*
X188186D01*
X184282Y-120269D02*
X187982D01*
X182516Y-118504D02*
X184282Y-120269D01*
X187982D02*
X189209Y-121496D01*
X177792Y-121653D02*
X180941Y-118504D01*
X182516D01*
X176217Y-123622D02*
X180941Y-128347D01*
X182516D01*
X162241Y-140004D02*
Y-135679D01*
X100729Y-119872D02*
Y-119871D01*
X66102Y-64085D02*
Y-58355D01*
X388083Y-134252D02*
Y-128731D01*
X373228Y-162598D02*
Y-155512D01*
X373083D02*
X373228D01*
X378346Y-161811D02*
Y-155512D01*
X378083D02*
X378346D01*
X393307Y-127165D02*
X396063D01*
X393307Y-143701D02*
Y-127165D01*
X373083Y-143701D02*
X393307D01*
X373083D02*
Y-134252D01*
X388713Y-128731D02*
Y-120866D01*
X378083Y-141339D02*
X391409D01*
Y-120866D01*
X388976D02*
X391409D01*
X378083Y-141339D02*
Y-134252D01*
X388713Y-120866D02*
X388976D01*
X388083Y-128731D02*
X388713D01*
X422835Y-137992D02*
Y-131791D01*
X427559Y-159646D02*
X427843D01*
X422835Y-166284D02*
Y-159646D01*
X415748Y-129609D02*
Y-126443D01*
X418898Y-129753D02*
Y-126443D01*
X422047Y-105643D02*
Y-101969D01*
X418898Y-105643D02*
Y-100000D01*
X275590Y-199606D02*
X278150Y-197047D01*
X278740D01*
X286811Y-197835D02*
X289370Y-200394D01*
X285039Y-197835D02*
X286811D01*
X272736Y-192126D02*
X273144Y-191719D01*
Y-190242D01*
X274803Y-188583D01*
X291831Y-197012D02*
Y-194095D01*
X292815Y-189764D02*
Y-187106D01*
X275807Y-184252D02*
X276102Y-183957D01*
X278346D01*
X275590Y-184252D02*
X275807D01*
X274803D02*
X275590D01*
X269783Y-189272D02*
X274803Y-184252D01*
X269783Y-192126D02*
Y-189272D01*
X272736Y-196457D02*
Y-192126D01*
X278734D02*
X278740Y-192132D01*
X272736Y-192126D02*
X278734D01*
X278740Y-192717D02*
Y-192132D01*
X289862Y-192224D02*
X291732Y-194095D01*
X289862Y-192224D02*
Y-189764D01*
X291732Y-194095D02*
X291831D01*
X286811Y-192717D02*
X289764Y-189764D01*
X285039Y-192717D02*
X286811D01*
X289764Y-189764D02*
X289862D01*
X283465Y-189370D02*
X285827Y-187008D01*
X283465Y-192717D02*
Y-189370D01*
X285827Y-187008D02*
Y-186909D01*
X278346Y-189094D02*
X280309Y-191056D01*
Y-192710D02*
X280315Y-192717D01*
X278346Y-189094D02*
Y-186909D01*
X280309Y-192710D02*
Y-191056D01*
X279528Y-200729D02*
X280315Y-199942D01*
Y-197835D01*
X279528Y-204429D02*
Y-200729D01*
X283465Y-199942D02*
X283858Y-200336D01*
Y-204429D02*
Y-200336D01*
X283465Y-199942D02*
Y-197835D01*
X281890Y-192717D02*
Y-188583D01*
Y-200771D02*
Y-197835D01*
X285039Y-195276D02*
X288583D01*
X275503D02*
X278740D01*
X321654Y-235040D02*
Y-232677D01*
Y-235040D02*
X323233Y-236619D01*
X336614Y-288779D02*
X337598Y-289764D01*
X336614Y-288779D02*
Y-286221D01*
X315945Y-287795D02*
X318701Y-290551D01*
X315333Y-299430D02*
X317913Y-296850D01*
X336811Y-299399D02*
Y-296063D01*
X341732Y-296069D02*
X341739Y-296063D01*
X341535Y-303150D02*
X341732Y-302953D01*
X341739Y-296063D02*
X341929D01*
X341732Y-302953D02*
Y-296069D01*
X341142Y-285036D02*
X341929Y-285824D01*
X341142Y-285036D02*
Y-281102D01*
X341929Y-289764D02*
Y-285824D01*
X333071Y-282480D02*
X336221D01*
X337598Y-281102D01*
X327953Y-282480D02*
X333071D01*
X323031Y-290551D02*
Y-287595D01*
X321850Y-286414D02*
Y-283465D01*
Y-286414D02*
X323031Y-287595D01*
X313386Y-283465D02*
X318307D01*
X311024D02*
X313386D01*
X308071Y-286417D02*
X311024Y-283465D01*
X308071Y-289370D02*
Y-286417D01*
X307283Y-298799D02*
X308268Y-299783D01*
X307283Y-298799D02*
Y-296457D01*
X308268Y-300000D02*
Y-299783D01*
Y-300000D02*
X311811Y-303543D01*
X317913D01*
X322139Y-302861D02*
X323301D01*
X323968Y-302194D02*
X324184D01*
X321457Y-303543D02*
X322139Y-302861D01*
X323301D02*
X323968Y-302194D01*
X324184D02*
X324803Y-301575D01*
Y-298622D01*
X323806Y-296850D02*
X323813Y-296857D01*
Y-297632D02*
Y-296857D01*
X323031Y-296850D02*
X323806D01*
X323813Y-297632D02*
X324803Y-298622D01*
X333071Y-296063D02*
X334639Y-294495D01*
X333071Y-299016D02*
Y-296063D01*
X336805Y-294495D02*
X336811Y-294488D01*
X334639Y-294495D02*
X336805D01*
X352362Y-288583D02*
X356693D01*
X351575Y-296063D02*
X355741D01*
X345749Y-295905D02*
X347874D01*
X341929Y-294488D02*
X344332D01*
X345749Y-295905D01*
X347874D02*
X348031Y-296063D01*
X344332Y-291339D02*
X346536Y-289134D01*
X348268D02*
X348819Y-288583D01*
X341929Y-291339D02*
X344332D01*
X346536Y-289134D02*
X348268D01*
X335532Y-291332D02*
X336805D01*
X333071Y-288871D02*
Y-286024D01*
X336805Y-291332D02*
X336811Y-291339D01*
X333071Y-288871D02*
X335532Y-291332D01*
X324311Y-292120D02*
X325790Y-290640D01*
Y-288186D02*
X327953Y-286024D01*
X323031Y-292126D02*
X323038Y-292120D01*
X324311D01*
X325790Y-290640D02*
Y-288186D01*
X314848Y-291184D02*
X315790Y-292126D01*
X311614Y-289370D02*
X313428Y-291184D01*
X315790Y-292126D02*
X317913D01*
X313428Y-291184D02*
X314848D01*
X314609Y-296457D02*
X315790Y-295276D01*
X317913D01*
X310827Y-296457D02*
X314609D01*
X324947Y-295276D02*
X326377Y-296706D01*
X326627D02*
X328740Y-298819D01*
X323031Y-295276D02*
X324947D01*
X326377Y-296706D02*
X326627D01*
X314961Y-293701D02*
X317913D01*
X320472Y-299569D02*
Y-296850D01*
X323031Y-293701D02*
X325776D01*
X320472Y-290551D02*
Y-287865D01*
X341929Y-292913D02*
X345161D01*
X333465D02*
X336811D01*
X339370Y-289764D02*
Y-286162D01*
Y-298819D02*
Y-296063D01*
X315158Y-236221D02*
Y-234252D01*
X320669Y-228740D01*
X324213D02*
X329134D01*
X330499Y-230105D01*
Y-235039D02*
Y-230105D01*
X328924Y-236614D02*
X330499Y-235039D01*
X328150Y-236614D02*
X328924D01*
X312322Y-236221D02*
X315158D01*
X309782Y-243307D02*
X312402D01*
X324213Y-250787D02*
X331299D01*
X334842Y-247244D01*
X312402Y-243307D02*
X319199Y-250105D01*
X319987D01*
X320669Y-250787D01*
X319685Y-245276D02*
Y-243701D01*
X320472Y-242913D01*
X323031D01*
X332087Y-238189D02*
X334449Y-235827D01*
X328150Y-238189D02*
X332087D01*
X318701Y-236221D02*
X320669Y-238189D01*
X323031D01*
X330512Y-242913D02*
X334842Y-247244D01*
X328150Y-242913D02*
X330512D01*
X331099Y-241339D02*
X332560Y-242799D01*
X334728D02*
X334842Y-242913D01*
X328150Y-241339D02*
X331099D01*
X332560Y-242799D02*
X334728D01*
X315945Y-243307D02*
X317913Y-241339D01*
X323031D01*
X328150Y-239764D02*
X333714D01*
X325590Y-246324D02*
Y-242913D01*
Y-236614D02*
Y-232344D01*
X317009Y-239764D02*
X323031D01*
X390643Y-226876D02*
Y-225180D01*
X390453Y-227067D02*
X390643Y-226876D01*
X389616Y-222982D02*
X398713D01*
X402010Y-219685D01*
X387894Y-224705D02*
X389616Y-222982D01*
X387894Y-227067D02*
Y-224705D01*
X378937Y-249803D02*
X382677D01*
X374213Y-241339D02*
X377270Y-238281D01*
X379239D01*
X379429Y-238090D01*
X374895Y-235931D02*
X376353D01*
X376753Y-235531D02*
X379429D01*
X374213Y-236614D02*
X374895Y-235931D01*
X376353D02*
X376753Y-235531D01*
X374902Y-217717D02*
X375197Y-218012D01*
Y-221260D02*
Y-218012D01*
X382776Y-221555D02*
Y-217913D01*
X375197Y-229528D02*
Y-221260D01*
Y-229528D02*
X376083Y-230413D01*
X379429D01*
X382776Y-227067D02*
Y-221555D01*
X428390Y-355832D02*
X436953D01*
X444827D02*
X449150D01*
X473173Y-356620D02*
X481441D01*
X489315D02*
X493234D01*
X529213Y-356296D02*
X533931D01*
X573701Y-356690D02*
X579072D01*
X624213Y-228346D02*
X626987D01*
X612598Y-261024D02*
X612623Y-260999D01*
Y-256717D01*
X612648Y-256693D01*
X612574Y-256619D02*
Y-252830D01*
X612500Y-252756D02*
X612574Y-252830D01*
Y-256619D02*
X612648Y-256693D01*
X616142Y-235433D02*
Y-232106D01*
X616929Y-231319D01*
X619685Y-229724D02*
X620866Y-228543D01*
X619685Y-235433D02*
Y-229724D01*
X614356Y-235419D02*
Y-228726D01*
Y-235419D02*
X614370Y-235433D01*
X614173Y-228543D02*
X614356Y-228726D01*
X618504Y-252362D02*
Y-251181D01*
X616156Y-248833D02*
X618504Y-251181D01*
X616156Y-248833D02*
Y-246593D01*
X616142Y-246579D02*
X616156Y-246593D01*
X605317Y-252756D02*
X609547D01*
X612584Y-252672D02*
Y-246593D01*
X612598Y-246579D01*
X612500Y-252756D02*
X612584Y-252672D01*
X604232Y-238976D02*
X607776Y-235433D01*
X610827D01*
X604232Y-242913D02*
X607898Y-246579D01*
X610827D01*
X610236Y-300000D02*
X612992Y-302756D01*
X605418Y-300000D02*
X610236D01*
X612992Y-302756D02*
X613128D01*
X227992Y-234680D02*
X230251Y-232421D01*
X224941Y-234680D02*
X227992D01*
X230251Y-232421D02*
Y-232266D01*
X225033Y-236588D02*
X228696D01*
X224941Y-236680D02*
X225033Y-236588D01*
X228696D02*
X230165Y-235119D01*
X229568Y-252680D02*
X230386Y-251861D01*
X224941Y-252680D02*
X229568D01*
X230386Y-251861D02*
X230406D01*
X204097Y-254724D02*
X206142Y-252680D01*
X209193D01*
X203937Y-254724D02*
X204097D01*
X205224Y-250772D02*
X209101D01*
X203805Y-252182D02*
X203815D01*
X209101Y-250772D02*
X209193Y-250680D01*
X203815Y-252182D02*
X205224Y-250772D01*
X203863Y-240622D02*
X209135D01*
X209193Y-240680D01*
X203805Y-240564D02*
X203863Y-240622D01*
X204153Y-238189D02*
X204644Y-238680D01*
X209193D01*
X203937Y-238189D02*
X204153D01*
X203937Y-235827D02*
X204790Y-236680D01*
X209193D01*
X204331Y-232869D02*
X206142Y-234680D01*
X209193D01*
X204331Y-232869D02*
Y-232677D01*
X389478Y-168898D02*
X393701D01*
X389478Y-173797D02*
Y-168898D01*
X387509Y-183071D02*
Y-173797D01*
X378594Y-166966D02*
X381604Y-169977D01*
Y-173797D02*
Y-169977D01*
X348031Y-168624D02*
X348139Y-168731D01*
Y-173797D02*
Y-168731D01*
X348031Y-168624D02*
Y-165748D01*
X346079Y-173705D02*
X346171Y-173797D01*
X346079Y-173705D02*
Y-170237D01*
X342808Y-166966D02*
X346079Y-170237D01*
X338297Y-180384D02*
Y-173797D01*
X337795Y-181102D02*
Y-180886D01*
X338297Y-180384D01*
X334252Y-180315D02*
X336328Y-178239D01*
Y-173797D01*
X326486Y-179059D02*
X326705D01*
X310236Y-165748D02*
X312706Y-168218D01*
Y-173797D02*
Y-168218D01*
Y-192300D02*
Y-189741D01*
X309490Y-195516D02*
X312706Y-192300D01*
X309208Y-195516D02*
X309490D01*
X309055Y-195669D02*
X309208Y-195516D01*
X314675Y-198819D02*
Y-189741D01*
X316643Y-194202D02*
X319291Y-196850D01*
X316643Y-194202D02*
Y-189741D01*
X322549Y-196063D02*
X322835D01*
X324517Y-194381D02*
Y-189741D01*
X322835Y-196063D02*
X324517Y-194381D01*
X322441Y-189741D02*
X322549D01*
X325407Y-184831D02*
X326486Y-185911D01*
X324705Y-184678D02*
X324858Y-184831D01*
X326486Y-189741D02*
Y-185911D01*
X324858Y-184831D02*
X325407D01*
X327658Y-184678D02*
X328454D01*
X331220Y-196266D02*
Y-196135D01*
X332391Y-194964D02*
Y-189741D01*
X331220Y-196135D02*
X332391Y-194964D01*
X336328Y-196489D02*
Y-189741D01*
Y-196489D02*
X337774D01*
X341774Y-196326D02*
Y-194095D01*
X338297D02*
X341774D01*
X338297D02*
Y-189741D01*
X362598Y-197244D02*
X363887D01*
Y-189741D01*
X373730Y-202888D02*
Y-189741D01*
X375698Y-197700D02*
Y-189741D01*
X380363Y-196740D02*
X381604D01*
Y-189741D01*
X383572Y-206205D02*
Y-189741D01*
X385541Y-202460D02*
Y-189741D01*
X394193Y-199606D02*
Y-197670D01*
X387509Y-199606D02*
X394193D01*
X387509D02*
Y-189741D01*
X389478Y-196440D02*
X389567D01*
X461417Y-245540D02*
X464472D01*
X461417Y-246484D02*
Y-245540D01*
X456545Y-246484D02*
X461417D01*
X463453Y-248452D02*
Y-247883D01*
X432732Y-284149D02*
X434437Y-285854D01*
X432579Y-283251D02*
X432732Y-283404D01*
X434437Y-285854D02*
X440601D01*
X432732Y-284149D02*
Y-283404D01*
Y-286965D02*
X433589Y-287822D01*
X432579Y-286400D02*
X432732Y-286553D01*
X433589Y-287822D02*
X440601D01*
X432732Y-286965D02*
Y-286553D01*
X432720Y-289791D02*
Y-289358D01*
X432835Y-291759D02*
Y-291755D01*
X269054Y-218915D02*
X278740D01*
X247146D02*
Y-218866D01*
X244213Y-248655D02*
X244410Y-248458D01*
X243996Y-248655D02*
X244213D01*
X245965Y-250655D02*
Y-250411D01*
X243996Y-252592D02*
Y-252379D01*
X245965Y-254655D02*
Y-254348D01*
X244028Y-258497D02*
Y-258285D01*
X245965Y-260497D02*
Y-260253D01*
X244028Y-262466D02*
Y-262222D01*
X245965Y-264497D02*
Y-264190D01*
X246162Y-293733D02*
Y-293718D01*
X280414Y-293782D02*
Y-293718D01*
Y-287812D02*
Y-287478D01*
Y-283875D02*
Y-283478D01*
X280382Y-274277D02*
Y-274033D01*
X269054Y-262222D02*
X279429D01*
X276755Y-250411D02*
Y-246539D01*
X269054Y-250411D02*
X276755D01*
X274719Y-248442D02*
Y-244928D01*
X269054Y-248442D02*
X274719D01*
X147047Y-33907D02*
X155427D01*
X147047Y-26033D02*
X155328D01*
X122539D02*
X129547D01*
X121457Y-57529D02*
X129547D01*
X451701Y-224857D02*
X456518D01*
X456545Y-224830D01*
X451674Y-224885D02*
X451701Y-224857D01*
X440628D02*
X445741D01*
X440601Y-224830D02*
X440628Y-224857D01*
X445741D02*
X445768Y-224885D01*
X451700Y-234700D02*
X456518D01*
X456545Y-234673D01*
X451674Y-234727D02*
X451700Y-234700D01*
X440628D02*
X445741D01*
X440601Y-234673D02*
X440628Y-234700D01*
X445741D02*
X445768Y-234727D01*
X451701Y-244542D02*
X456518D01*
X451674Y-244570D02*
X451701Y-244542D01*
X456518D02*
X456545Y-244515D01*
X440628Y-244542D02*
X445741D01*
X440601Y-244515D02*
X440628Y-244542D01*
X445741D02*
X445768Y-244570D01*
X451685Y-254369D02*
X456534D01*
X451674Y-254381D02*
X451685Y-254369D01*
X456534D02*
X456545Y-254358D01*
X440612Y-254369D02*
X445757D01*
X440601Y-254358D02*
X440612Y-254369D01*
X445757D02*
X445768Y-254381D01*
X451701Y-264227D02*
X456518D01*
X456545Y-264200D01*
X451674Y-264255D02*
X451701Y-264227D01*
X440628D02*
X445741D01*
X440601Y-264200D02*
X440628Y-264227D01*
X445741D02*
X445768Y-264255D01*
X451674Y-275261D02*
X451890D01*
X456453Y-274135D02*
X456545Y-274043D01*
X453016Y-274135D02*
X456453D01*
X451890Y-275261D02*
X453016Y-274135D01*
X444550Y-274043D02*
X445768Y-275261D01*
X440601Y-274043D02*
X444550D01*
X451701Y-283912D02*
X456518D01*
X456545Y-283885D01*
X451674Y-283940D02*
X451701Y-283912D01*
X440628D02*
X445741D01*
X440601Y-283885D02*
X440628Y-283912D01*
X445741D02*
X445768Y-283940D01*
X263161Y-285805D02*
X269014D01*
X269054Y-285844D01*
X263122Y-285766D02*
X263161Y-285805D01*
X253149D02*
X258582D01*
X258622Y-285766D01*
X253110Y-285844D02*
X253149Y-285805D01*
X263322Y-276066D02*
X263354Y-276033D01*
X269022D02*
X269054Y-276001D01*
X263354Y-276033D02*
X269022D01*
X253142D02*
X258589D01*
X253110Y-276001D02*
X253142Y-276033D01*
X258589D02*
X258622Y-276066D01*
X263138Y-265040D02*
X264258Y-266159D01*
X269054D01*
X262922Y-265040D02*
X263138D01*
X257361Y-266159D02*
X258661Y-264859D01*
X253110Y-266159D02*
X257361D01*
X258661Y-264859D02*
X258702D01*
X263802Y-256408D02*
X268962D01*
X269054Y-256316D01*
X263681Y-256529D02*
X263802Y-256408D01*
X253202D02*
X258640D01*
X253110Y-256316D02*
X253202Y-256408D01*
X258640D02*
X258760Y-256529D01*
X263326Y-246470D02*
X269049D01*
X269054Y-246474D01*
X263322Y-246466D02*
X263326Y-246470D01*
X253114D02*
X258617D01*
X253110Y-246474D02*
X253114Y-246470D01*
X258617D02*
X258622Y-246466D01*
X263639Y-236649D02*
X269037D01*
X269054Y-236631D01*
X263622Y-236666D02*
X263639Y-236649D01*
X253143Y-236598D02*
X258989D01*
X253110Y-236631D02*
X253143Y-236598D01*
X258989D02*
X259022Y-236566D01*
X263657Y-226866D02*
X268977D01*
X269054Y-226789D01*
X263580Y-226943D02*
X263657Y-226866D01*
X253122Y-226778D02*
X258910D01*
X253110Y-226789D02*
X253122Y-226778D01*
X258910D02*
X258922Y-226766D01*
X320526Y-179063D02*
Y-173851D01*
X320580Y-173797D01*
X320473Y-179117D02*
X320526Y-179063D01*
X330423Y-178717D02*
X330705Y-178999D01*
Y-179215D02*
Y-178999D01*
X330423Y-178717D02*
Y-173797D01*
Y-184934D02*
X331091Y-184266D01*
X330423Y-189741D02*
Y-184934D01*
X331091Y-184266D02*
Y-184050D01*
X340261Y-189737D02*
Y-183846D01*
Y-189737D02*
X340265Y-189741D01*
X340256Y-183841D02*
X340261Y-183846D01*
X340265Y-178417D02*
X340847Y-178999D01*
X340265Y-178417D02*
Y-173797D01*
X340847Y-179215D02*
Y-178999D01*
X350200Y-189649D02*
Y-183673D01*
X350108Y-189741D02*
X350200Y-189649D01*
Y-183673D02*
X350327Y-183546D01*
X350200Y-179088D02*
Y-173889D01*
X350108Y-173797D02*
X350200Y-173889D01*
Y-179088D02*
X350327Y-179215D01*
X360042Y-179119D02*
Y-173889D01*
X359950Y-173797D02*
X360042Y-173889D01*
Y-179119D02*
X360138Y-179215D01*
X359874Y-183841D02*
X359912Y-183879D01*
Y-189703D02*
X359950Y-189741D01*
X359912Y-189703D02*
Y-183879D01*
X369793Y-173797D02*
X369885Y-173889D01*
Y-179120D02*
Y-173889D01*
Y-179120D02*
X369981Y-179215D01*
X379566Y-179145D02*
Y-173866D01*
X379635Y-173797D01*
X379496Y-179215D02*
X379566Y-179145D01*
Y-189672D02*
Y-183872D01*
Y-189672D02*
X379635Y-189741D01*
X379496Y-183803D02*
X379566Y-183872D01*
X369739Y-189687D02*
Y-183895D01*
Y-189687D02*
X369793Y-189741D01*
X369685Y-183841D02*
X369739Y-183895D01*
X131790Y-353367D02*
X132171Y-353853D01*
X131004Y-352362D02*
X131668Y-353143D01*
X131004Y-352362D02*
Y-348031D01*
X132171Y-353853D02*
X132337Y-354066D01*
X134122Y-354724D02*
X164173D01*
X166929Y-357480D01*
X21949Y-338779D02*
X22047Y-338681D01*
Y-335433D01*
X2097Y-349213D02*
X5647D01*
X27067Y-286024D02*
Y-282677D01*
X5584Y-238905D02*
Y-237795D01*
X27067Y-228937D02*
X35120D01*
X10372Y-193307D02*
X10501Y-193436D01*
Y-197509D02*
Y-193436D01*
Y-197509D02*
X10630Y-197638D01*
X19976Y-220472D02*
Y-216437D01*
Y-204823D02*
Y-200787D01*
X27067Y-181299D02*
X27165Y-181201D01*
Y-179134D01*
X-7874Y-188976D02*
X-5709D01*
X-3937Y-187205D01*
X381595Y-332581D02*
X381989Y-332188D01*
Y-331971D01*
X370178Y-315259D02*
Y-315042D01*
X369784Y-315652D02*
X370178Y-315259D01*
X342225Y-315691D02*
X342618Y-315298D01*
Y-315081D01*
X364272Y-315259D02*
Y-315042D01*
X363878Y-315653D02*
X364272Y-315259D01*
X342225Y-333369D02*
X343012Y-332581D01*
Y-332365D01*
X322540Y-332975D02*
X322933Y-332581D01*
Y-332365D01*
X375689Y-316046D02*
X376477Y-315259D01*
Y-315042D01*
X357973Y-315042D02*
X357973Y-315042D01*
X332776Y-332581D02*
Y-332365D01*
X332382Y-332975D02*
X332776Y-332581D01*
X332382Y-321933D02*
X332382Y-321933D01*
Y-315042D02*
X332382Y-315042D01*
X19976Y-326772D02*
Y-322736D01*
Y-311122D02*
Y-307087D01*
Y-272638D02*
Y-268602D01*
Y-256988D02*
Y-252953D01*
X-8465Y-316929D02*
Y-316781D01*
X13973Y-335433D02*
Y-316929D01*
X1181Y-335433D02*
X13973D01*
X4331Y-345965D02*
Y-344488D01*
X-1181Y-345965D02*
X4331D01*
X6102Y-342717D02*
X9547D01*
X4331Y-344488D02*
X6102Y-342717D01*
X-8465Y-262795D02*
X13973D01*
X-8465Y-263630D02*
Y-262795D01*
X2756Y-280709D02*
X9055D01*
X13973Y-270866D02*
Y-262795D01*
X9055Y-270866D02*
X13973D01*
X9055Y-280709D02*
Y-270866D01*
X2756Y-283071D02*
Y-280709D01*
X11024Y-286024D02*
Y-283858D01*
Y-287992D02*
Y-286024D01*
X14665D01*
X14567Y-283858D02*
Y-280709D01*
X11024Y-283858D02*
X14567D01*
X11024Y-287992D02*
X14665D01*
X27067Y-289961D02*
X35039D01*
X27067Y-287992D02*
X32874D01*
X35039Y-285827D01*
X27067Y-298727D02*
Y-291929D01*
X14475Y-290151D02*
X14665Y-289961D01*
X12605Y-290151D02*
X14475D01*
X10630Y-292126D02*
X12605Y-290151D01*
X14173Y-294320D02*
Y-291929D01*
X14665D01*
X14173Y-296986D02*
Y-294320D01*
X-8465Y-210630D02*
Y-210480D01*
X13973Y-215748D02*
Y-210630D01*
X11417Y-215748D02*
X13973D01*
X11417Y-220472D02*
Y-215748D01*
Y-228937D02*
Y-225984D01*
Y-230906D02*
Y-228937D01*
X14665D01*
X11417Y-230906D02*
X14665D01*
X288Y-234968D02*
Y-234646D01*
X10007D02*
Y-232874D01*
Y-234968D02*
Y-234646D01*
Y-232874D02*
X14665D01*
X19685Y-239370D02*
X23524D01*
X35039D02*
Y-237402D01*
X26870Y-239370D02*
X35039D01*
X11282Y-237795D02*
X14665D01*
Y-237402D01*
Y-234842D01*
X27067Y-232874D02*
X34055D01*
X36220Y-235039D01*
X34843Y-230906D02*
X36614Y-232677D01*
X27067Y-230906D02*
X34843D01*
X32480Y-234842D02*
X35039Y-237402D01*
X27067Y-234842D02*
X32480D01*
X-8465Y-157332D02*
X13973D01*
Y-162992D02*
Y-157332D01*
X10236Y-162992D02*
X13973D01*
X10236Y-175591D02*
Y-162992D01*
X7480Y-175591D02*
X10236D01*
X7480Y-178543D02*
Y-175591D01*
X2756Y-178543D02*
X7480D01*
X30709Y-192520D02*
Y-190411D01*
Y-187205D01*
X33071Y-185755D02*
Y-185236D01*
X35827Y-185755D02*
Y-183268D01*
X27067D02*
X35827D01*
X13780Y-193307D02*
Y-190551D01*
X13250Y-193307D02*
X13780D01*
X14475Y-189639D02*
Y-187395D01*
X13780Y-190335D02*
X14475Y-189639D01*
X13780Y-190551D02*
Y-190335D01*
X14475Y-187395D02*
X14665Y-187205D01*
X9843Y-185755D02*
Y-185236D01*
X27067Y-187205D02*
X30709D01*
X26476Y-192520D02*
X30709D01*
X19682D02*
X23130D01*
X11024Y-181299D02*
Y-179134D01*
Y-183268D02*
Y-181299D01*
X14665D01*
X15748Y-179134D02*
Y-175591D01*
X11024Y-179134D02*
X15748D01*
X11024Y-183268D02*
X14665D01*
X15748Y-175591D02*
X16142Y-175984D01*
X134350Y-352362D02*
X141387D01*
X134350Y-348031D02*
X142126D01*
X198392Y-366842D02*
X225503D01*
X166929Y-370866D02*
Y-357480D01*
Y-370866D02*
X173474Y-377411D01*
X178543D01*
X31693Y4921D02*
X36614D01*
X31693Y18701D02*
X36614D01*
X31693Y11811D02*
X36762D01*
X2756Y-178543D02*
X2854Y-178445D01*
X-20122Y-342673D02*
X-19685Y-343110D01*
X-23469Y-342673D02*
X-20122D01*
X-23622Y-342520D02*
X-23469Y-342673D01*
X-23622Y-290354D02*
X-19685D01*
X-23469Y-286570D02*
X-19926D01*
X-19685Y-286811D01*
X-23622Y-286417D02*
X-23469Y-286570D01*
Y-282633D02*
X-18843D01*
X-23622Y-282480D02*
X-23469Y-282633D01*
X-18843D02*
X-18406Y-283071D01*
X-23469Y-237052D02*
X-19926D01*
X-23622Y-237205D02*
X-23469Y-237052D01*
X-19926D02*
X-19685Y-236811D01*
X-23622Y-233268D02*
X-19685D01*
X-23622Y-229331D02*
X-23524Y-229429D01*
X-18504D02*
X-18406Y-229528D01*
X-23524Y-229429D02*
X-18504D01*
X-23622Y-339567D02*
X-19685D01*
X-23622Y-335630D02*
X-23524Y-335728D01*
X-18504D02*
X-18406Y-335827D01*
X-23524Y-335728D02*
X-18504D01*
X-23622Y-184055D02*
X-19685D01*
X-23469Y-177012D02*
X-18646D01*
X-18406Y-176772D01*
X-23622Y-177165D02*
X-23469Y-177012D01*
X-23622Y-110236D02*
X-19685D01*
X-23469Y-106452D02*
X-19926D01*
X-19685Y-106693D01*
X-23622Y-106299D02*
X-23469Y-106452D01*
X-18843Y-102515D02*
X-18406Y-102953D01*
X-23469Y-102515D02*
X-18843D01*
X-23622Y-102362D02*
X-23469Y-102515D01*
X-23622Y-66929D02*
X-19685D01*
X-23469Y-63145D02*
X-19926D01*
X-19685Y-63386D01*
X-23622Y-62992D02*
X-23469Y-63145D01*
Y-59886D02*
X-18646D01*
X-23622Y-60039D02*
X-23469Y-59886D01*
X-18646D02*
X-18406Y-59646D01*
X276969Y-399280D02*
X277165Y-399477D01*
X222047Y-401427D02*
X222244Y-401230D01*
Y-388041D01*
X225394Y-384891D01*
X277244Y-402150D02*
X277441Y-401953D01*
X134744Y-347244D02*
X134941Y-347441D01*
D32*
X383465Y-109055D02*
Y-103543D01*
X390654Y-109666D02*
Y-104510D01*
X383268Y-109055D02*
X383465D01*
X267547Y-356432D02*
Y-360430D01*
X268880Y-361763D01*
X270213Y-360430D01*
X271545Y-361763D01*
X272878Y-360430D01*
Y-356432D01*
X275544D02*
Y-360430D01*
X276877Y-361763D01*
X278210Y-360430D01*
X279543Y-361763D01*
X280876Y-360430D01*
Y-356432D01*
X283542D02*
Y-360430D01*
X284875Y-361763D01*
X286207Y-360430D01*
X287540Y-361763D01*
X288873Y-360430D01*
Y-356432D01*
X291539Y-361763D02*
Y-360430D01*
X292872D01*
Y-361763D01*
X291539D01*
X299536Y-355099D02*
Y-356432D01*
X298203D01*
X300869D01*
X299536D01*
Y-360430D01*
X300869Y-361763D01*
X304868D02*
X307534D01*
X306201D01*
Y-356432D01*
X304868D01*
X311532Y-361763D02*
Y-356432D01*
X312865D01*
X314198Y-357765D01*
Y-361763D01*
Y-357765D01*
X315531Y-356432D01*
X316864Y-357765D01*
Y-361763D01*
X319530D02*
X322196D01*
X320863D01*
Y-356432D01*
X319530D01*
X326194Y-361763D02*
Y-356432D01*
X330193D01*
X331526Y-357765D01*
Y-361763D01*
X336858Y-364429D02*
X338191D01*
X339523Y-363096D01*
Y-356432D01*
X335525D01*
X334192Y-357765D01*
Y-360430D01*
X335525Y-361763D01*
X339523D01*
X347521Y-356432D02*
X343522D01*
X342189Y-357765D01*
Y-360430D01*
X343522Y-361763D01*
X347521D01*
X351519Y-356432D02*
X354185D01*
X355518Y-357765D01*
Y-361763D01*
X351519D01*
X350187Y-360430D01*
X351519Y-359098D01*
X355518D01*
X358184Y-356432D02*
Y-361763D01*
Y-359098D01*
X359517Y-357765D01*
X360850Y-356432D01*
X362183D01*
X371513Y-353766D02*
Y-361763D01*
X367514D01*
X366181Y-360430D01*
Y-357765D01*
X367514Y-356432D01*
X371513D01*
X374179Y-361763D02*
Y-360430D01*
X375512D01*
Y-361763D01*
X374179D01*
X386175Y-356432D02*
X382176D01*
X380843Y-357765D01*
Y-360430D01*
X382176Y-361763D01*
X386175D01*
X390174D02*
X392840D01*
X394172Y-360430D01*
Y-357765D01*
X392840Y-356432D01*
X390174D01*
X388841Y-357765D01*
Y-360430D01*
X390174Y-361763D01*
X396838D02*
Y-356432D01*
X398171D01*
X399504Y-357765D01*
Y-361763D01*
Y-357765D01*
X400837Y-356432D01*
X402170Y-357765D01*
Y-361763D01*
D38*
X84981Y-123809D02*
D03*
D39*
X79076Y-114655D02*
D03*
X81044D02*
D03*
X83013D02*
D03*
X84981D02*
D03*
X86950D02*
D03*
X88918D02*
D03*
X90887D02*
D03*
X90887Y-132963D02*
D03*
X88918D02*
D03*
X86950D02*
D03*
X84981D02*
D03*
X83013D02*
D03*
X81044D02*
D03*
X79076D02*
D03*
D40*
X94135Y-117904D02*
D03*
Y-119872D02*
D03*
Y-121841D02*
D03*
Y-123809D02*
D03*
Y-125778D02*
D03*
Y-127746D02*
D03*
Y-129715D02*
D03*
X75828Y-125778D02*
D03*
Y-123809D02*
D03*
Y-121841D02*
D03*
Y-119872D02*
D03*
Y-117904D02*
D03*
Y-127746D02*
D03*
Y-129715D02*
D03*
D41*
X58407Y-133652D02*
D03*
X64312D02*
D03*
D42*
X47777Y-115541D02*
D03*
X50926D02*
D03*
X50926Y-111604D02*
D03*
X47777D02*
D03*
X50926Y-108061D02*
D03*
X47777D02*
D03*
X160236Y-54331D02*
D03*
X163386D02*
D03*
X544882Y-300787D02*
D03*
X541732D02*
D03*
X160236Y-59055D02*
D03*
X163386D02*
D03*
X548819Y-300787D02*
D03*
X551968D02*
D03*
X181335Y-132874D02*
D03*
X184485D02*
D03*
X181335Y-113583D02*
D03*
X184485D02*
D03*
D43*
X63918Y-121053D02*
D03*
Y-126565D02*
D03*
X253082Y-115065D02*
D03*
Y-120577D02*
D03*
X611811Y-38189D02*
D03*
Y-43701D02*
D03*
D44*
X57422Y-120856D02*
D03*
Y-125581D02*
D03*
D45*
X58210Y-108061D02*
D03*
X64903D02*
D03*
D46*
X128523Y-116147D02*
D03*
X134034D02*
D03*
X128459Y-110462D02*
D03*
X133971D02*
D03*
D47*
X262456Y-120276D02*
D03*
Y-113189D02*
D03*
X620866Y-35827D02*
D03*
Y-42913D02*
D03*
D48*
X264469Y-128937D02*
D03*
X276083D02*
D03*
Y-141142D02*
D03*
X264469D02*
D03*
X276083Y-152559D02*
D03*
X264469D02*
D03*
D49*
X436811Y-137992D02*
D03*
Y-144095D02*
D03*
Y-159646D02*
D03*
Y-153543D02*
D03*
X408858Y-137992D02*
D03*
Y-144095D02*
D03*
Y-153543D02*
D03*
Y-159646D02*
D03*
X47441Y-27362D02*
D03*
Y-21260D02*
D03*
Y-5709D02*
D03*
Y-11811D02*
D03*
X75394Y-27362D02*
D03*
Y-21260D02*
D03*
Y-11811D02*
D03*
Y-5709D02*
D03*
D50*
X427559Y-137992D02*
D03*
X422835D02*
D03*
X418110D02*
D03*
Y-159646D02*
D03*
X422835D02*
D03*
X427559D02*
D03*
Y-148819D02*
D03*
X422835D02*
D03*
X418110D02*
D03*
X427559Y-153543D02*
D03*
X422835D02*
D03*
X418110D02*
D03*
X422835Y-144095D02*
D03*
X418110D02*
D03*
X61417Y-21260D02*
D03*
Y-16535D02*
D03*
X56693Y-27362D02*
D03*
X61417D02*
D03*
X66142D02*
D03*
Y-5709D02*
D03*
X61417D02*
D03*
X56693D02*
D03*
Y-16535D02*
D03*
X66142D02*
D03*
X56693Y-11811D02*
D03*
X61417D02*
D03*
X66142D02*
D03*
Y-21260D02*
D03*
D51*
X427409Y-144269D02*
D03*
X56843Y-21085D02*
D03*
D52*
X159390Y-99990D02*
D03*
Y-101565D02*
D03*
Y-103139D02*
D03*
X163445D02*
D03*
Y-101565D02*
D03*
Y-99990D02*
D03*
D53*
X161417Y-101565D02*
D03*
D54*
X109095Y12205D02*
D03*
X85394D02*
D03*
X72480Y12598D02*
D03*
X48779D02*
D03*
X334567Y-133858D02*
D03*
X358268D02*
D03*
X83819Y-77165D02*
D03*
X107520D02*
D03*
D55*
X382776Y-241437D02*
D03*
X385335D02*
D03*
X387894D02*
D03*
X390453D02*
D03*
Y-227067D02*
D03*
X387894D02*
D03*
X385335D02*
D03*
X382776D02*
D03*
D56*
X393799Y-238090D02*
D03*
Y-235531D02*
D03*
Y-232972D02*
D03*
Y-230413D02*
D03*
X379429D02*
D03*
Y-232972D02*
D03*
Y-235531D02*
D03*
Y-238090D02*
D03*
D57*
X609547Y-277461D02*
D03*
Y-280020D02*
D03*
Y-274902D02*
D03*
Y-282579D02*
D03*
Y-285138D02*
D03*
D58*
X620079Y-284547D02*
D03*
Y-275492D02*
D03*
D59*
X147047Y-26033D02*
D03*
Y-33907D02*
D03*
Y-41781D02*
D03*
Y-49655D02*
D03*
X129547Y-26033D02*
D03*
Y-33907D02*
D03*
Y-41781D02*
D03*
Y-18159D02*
D03*
Y-73277D02*
D03*
Y-57529D02*
D03*
Y-65403D02*
D03*
Y-49655D02*
D03*
X147047Y-73277D02*
D03*
Y-65403D02*
D03*
Y-57529D02*
D03*
Y-18159D02*
D03*
Y-49655D02*
D03*
Y-57529D02*
D03*
Y-65403D02*
D03*
Y-73277D02*
D03*
X129547Y-49655D02*
D03*
Y-65403D02*
D03*
Y-57529D02*
D03*
Y-73277D02*
D03*
D60*
X133957Y-9843D02*
D03*
X136909D02*
D03*
X489862Y-314173D02*
D03*
X492815D02*
D03*
X177657Y-87795D02*
D03*
X180610D02*
D03*
X178051Y-101181D02*
D03*
X181004D02*
D03*
X201476Y-87795D02*
D03*
X198524D02*
D03*
X200295Y-102756D02*
D03*
X197343D02*
D03*
X180610Y-92126D02*
D03*
X177657D02*
D03*
X198524Y-91732D02*
D03*
X201476D02*
D03*
X609547Y-252756D02*
D03*
X612500D02*
D03*
X294783Y-194095D02*
D03*
X291831D02*
D03*
X292815Y-189764D02*
D03*
X289862D02*
D03*
X269783Y-192126D02*
D03*
X272736D02*
D03*
X269783Y-196457D02*
D03*
X272736D02*
D03*
D61*
X597835Y-233071D02*
D03*
X603740D02*
D03*
X605905Y-186107D02*
D03*
X600000D02*
D03*
X600591Y-150000D02*
D03*
X594685D02*
D03*
X457480Y-76378D02*
D03*
X451575D02*
D03*
X92323Y-92126D02*
D03*
X98228D02*
D03*
X597835Y-220472D02*
D03*
X603740D02*
D03*
X597835Y-226772D02*
D03*
X603740D02*
D03*
X31693Y-1969D02*
D03*
X25787D02*
D03*
X31693Y4921D02*
D03*
X25787D02*
D03*
X31693Y11811D02*
D03*
X25787D02*
D03*
X31693Y18701D02*
D03*
X25787D02*
D03*
D62*
X595036Y-211353D02*
D03*
Y-206353D02*
D03*
Y-201353D02*
D03*
Y-196353D02*
D03*
X624918D02*
D03*
Y-201353D02*
D03*
Y-206353D02*
D03*
Y-211353D02*
D03*
D63*
X590530Y-163898D02*
D03*
Y-173898D02*
D03*
X624430Y-163898D02*
D03*
Y-173898D02*
D03*
D64*
X599016Y-144488D02*
D03*
X595472D02*
D03*
X492323Y-303543D02*
D03*
X495866D02*
D03*
X484842Y-317717D02*
D03*
X488386D02*
D03*
X489567Y-310236D02*
D03*
X493110D02*
D03*
X473819Y-315354D02*
D03*
X470276D02*
D03*
X144685Y-11811D02*
D03*
X141142D02*
D03*
X137598Y-6299D02*
D03*
X134055D02*
D03*
X312402Y-243307D02*
D03*
X315945D02*
D03*
X370669Y-236614D02*
D03*
X374213D02*
D03*
X370669Y-241339D02*
D03*
X374213D02*
D03*
X396654Y-219291D02*
D03*
X393110D02*
D03*
X337992Y-235827D02*
D03*
X334449D02*
D03*
X320669Y-250787D02*
D03*
X324213D02*
D03*
X320669Y-228740D02*
D03*
X324213D02*
D03*
X338386Y-242913D02*
D03*
X334842D02*
D03*
X315158Y-236221D02*
D03*
X318701D02*
D03*
X337598Y-281102D02*
D03*
X341142D02*
D03*
X337992Y-303150D02*
D03*
X341535D02*
D03*
X318307Y-283465D02*
D03*
X321850D02*
D03*
X317913Y-303543D02*
D03*
X321457D02*
D03*
X600689Y-238976D02*
D03*
X604232D02*
D03*
X352362Y-288583D02*
D03*
X348819D02*
D03*
X351575Y-296063D02*
D03*
X348031D02*
D03*
X308071Y-289370D02*
D03*
X311614D02*
D03*
X307283Y-296457D02*
D03*
X310827D02*
D03*
X600689Y-242913D02*
D03*
X604232D02*
D03*
X613976Y-228740D02*
D03*
X610433D02*
D03*
X620669Y-228346D02*
D03*
X624213D02*
D03*
D65*
X478346Y-303937D02*
D03*
X150787Y394D02*
D03*
D66*
X475394Y-298237D02*
D03*
X477362D02*
D03*
X479331D02*
D03*
X481299D02*
D03*
Y-309637D02*
D03*
X479331D02*
D03*
X477362D02*
D03*
X475394D02*
D03*
X147835Y6094D02*
D03*
X149803D02*
D03*
X151772D02*
D03*
X153740D02*
D03*
Y-5306D02*
D03*
X151772D02*
D03*
X149803D02*
D03*
X147835D02*
D03*
D67*
X484047Y-300984D02*
D03*
Y-302953D02*
D03*
Y-304921D02*
D03*
Y-306890D02*
D03*
X472647D02*
D03*
Y-304921D02*
D03*
Y-302953D02*
D03*
Y-300984D02*
D03*
X156487Y3347D02*
D03*
Y1378D02*
D03*
Y-591D02*
D03*
Y-2559D02*
D03*
X145087D02*
D03*
Y-591D02*
D03*
Y1378D02*
D03*
Y3347D02*
D03*
D68*
X482677Y-276476D02*
D03*
Y-279429D02*
D03*
X483071Y-256988D02*
D03*
Y-254035D02*
D03*
X479921Y-279429D02*
D03*
Y-276476D02*
D03*
X485827Y-279429D02*
D03*
Y-276476D02*
D03*
X476772Y-254035D02*
D03*
Y-256988D02*
D03*
X487402Y-254035D02*
D03*
Y-256988D02*
D03*
X465748Y-308760D02*
D03*
Y-311713D02*
D03*
X488583Y-295177D02*
D03*
Y-292224D02*
D03*
X472835Y-292028D02*
D03*
Y-289075D02*
D03*
X146850Y14272D02*
D03*
Y17224D02*
D03*
X164567Y9941D02*
D03*
Y12894D02*
D03*
X158661Y-9941D02*
D03*
Y-12894D02*
D03*
X283858Y-204232D02*
D03*
Y-207185D02*
D03*
X285827Y-186909D02*
D03*
Y-183957D02*
D03*
X279528Y-204429D02*
D03*
Y-207382D02*
D03*
X278346Y-186909D02*
D03*
Y-183957D02*
D03*
D69*
X461417Y-308465D02*
D03*
Y-312008D02*
D03*
X476772Y-291929D02*
D03*
Y-288386D02*
D03*
X483465Y-291535D02*
D03*
Y-287992D02*
D03*
X466142Y-298228D02*
D03*
Y-294685D02*
D03*
X142520Y13189D02*
D03*
Y16732D02*
D03*
X162598Y-9646D02*
D03*
Y-13189D02*
D03*
X159843Y9646D02*
D03*
Y13189D02*
D03*
X151181Y14370D02*
D03*
Y17913D02*
D03*
X153543Y-10433D02*
D03*
Y-13976D02*
D03*
X169291Y9646D02*
D03*
Y13189D02*
D03*
X382677Y-249803D02*
D03*
Y-246260D02*
D03*
X333071Y-282480D02*
D03*
Y-286024D02*
D03*
Y-302559D02*
D03*
Y-299016D02*
D03*
X327953Y-282480D02*
D03*
Y-286024D02*
D03*
X328740Y-302362D02*
D03*
Y-298819D02*
D03*
D70*
X203839Y-56693D02*
D03*
X174114Y-2559D02*
D03*
X203839Y-3543D02*
D03*
X174114Y-4528D02*
D03*
X203839Y-5512D02*
D03*
X174114Y-6496D02*
D03*
X203839Y-7480D02*
D03*
X174114Y-8465D02*
D03*
X203839Y-9449D02*
D03*
X174114Y-10433D02*
D03*
X203839Y-11417D02*
D03*
X174114Y-12402D02*
D03*
X203839Y-13386D02*
D03*
X174114Y-14370D02*
D03*
X203839Y-15354D02*
D03*
X174114Y-16339D02*
D03*
X203839Y-17323D02*
D03*
X174114Y-18307D02*
D03*
X203839Y-19291D02*
D03*
X174114Y-20276D02*
D03*
X203839Y-21260D02*
D03*
X174114Y-22244D02*
D03*
X203839Y-23228D02*
D03*
X174114Y-24213D02*
D03*
X203839Y-25197D02*
D03*
X174114Y-26181D02*
D03*
X203839Y-27165D02*
D03*
X174114Y-28150D02*
D03*
X203839Y-29134D02*
D03*
X174114Y-30118D02*
D03*
X203839Y-31102D02*
D03*
X174114Y-32087D02*
D03*
X203839Y-33071D02*
D03*
X174114Y-34055D02*
D03*
X203839Y-35039D02*
D03*
X174114Y-36024D02*
D03*
X203839Y-37008D02*
D03*
X174114Y-37992D02*
D03*
X203839Y-38976D02*
D03*
X174114Y-39961D02*
D03*
X203839Y-40945D02*
D03*
X174114Y-41929D02*
D03*
X203839Y-42913D02*
D03*
X174114Y-43898D02*
D03*
X203839Y-44882D02*
D03*
X174114Y-45866D02*
D03*
X203839Y-46850D02*
D03*
X174114Y-47835D02*
D03*
X203839Y-48819D02*
D03*
X174114Y-49803D02*
D03*
X203839Y-50787D02*
D03*
X174114Y-51772D02*
D03*
X203839Y-52756D02*
D03*
X174114Y-53740D02*
D03*
X203839Y-54724D02*
D03*
X174114Y-55709D02*
D03*
X203839Y-66535D02*
D03*
Y-68504D02*
D03*
Y-70472D02*
D03*
Y-72441D02*
D03*
Y-74410D02*
D03*
X174114Y-65551D02*
D03*
Y-67520D02*
D03*
Y-69488D02*
D03*
Y-71457D02*
D03*
Y-73425D02*
D03*
Y-75394D02*
D03*
D71*
X177165Y1772D02*
D03*
Y-79724D02*
D03*
D72*
X553543Y-262402D02*
D03*
X499409Y-292126D02*
D03*
X500394Y-262402D02*
D03*
X501378Y-292126D02*
D03*
X502362Y-262402D02*
D03*
X503346Y-292126D02*
D03*
X504331Y-262402D02*
D03*
X505315Y-292126D02*
D03*
X506299Y-262402D02*
D03*
X507283Y-292126D02*
D03*
X508268Y-262402D02*
D03*
X509252Y-292126D02*
D03*
X510236Y-262402D02*
D03*
X511221Y-292126D02*
D03*
X512205Y-262402D02*
D03*
X513189Y-292126D02*
D03*
X514173Y-262402D02*
D03*
X515158Y-292126D02*
D03*
X516142Y-262402D02*
D03*
X517126Y-292126D02*
D03*
X518110Y-262402D02*
D03*
X519095Y-292126D02*
D03*
X520079Y-262402D02*
D03*
X521063Y-292126D02*
D03*
X522047Y-262402D02*
D03*
X523032Y-292126D02*
D03*
X524016Y-262402D02*
D03*
X525000Y-292126D02*
D03*
X525984Y-262402D02*
D03*
X526968Y-292126D02*
D03*
X527953Y-262402D02*
D03*
X528937Y-292126D02*
D03*
X529921Y-262402D02*
D03*
X530905Y-292126D02*
D03*
X531890Y-262402D02*
D03*
X532874Y-292126D02*
D03*
X533858Y-262402D02*
D03*
X534842Y-292126D02*
D03*
X535827Y-262402D02*
D03*
X536811Y-292126D02*
D03*
X537795Y-262402D02*
D03*
X538779Y-292126D02*
D03*
X539764Y-262402D02*
D03*
X540748Y-292126D02*
D03*
X541732Y-262402D02*
D03*
X542717Y-292126D02*
D03*
X543701Y-262402D02*
D03*
X544685Y-292126D02*
D03*
X545669Y-262402D02*
D03*
X546654Y-292126D02*
D03*
X547638Y-262402D02*
D03*
X548622Y-292126D02*
D03*
X549606Y-262402D02*
D03*
X550591Y-292126D02*
D03*
X551575Y-262402D02*
D03*
X552559Y-292126D02*
D03*
X563386Y-262402D02*
D03*
X565354D02*
D03*
X567323D02*
D03*
X569291D02*
D03*
X571260D02*
D03*
X562402Y-292126D02*
D03*
X564370D02*
D03*
X566339D02*
D03*
X568307D02*
D03*
X570276D02*
D03*
X572244D02*
D03*
D73*
X495079Y-289075D02*
D03*
X576575D02*
D03*
D74*
X545448Y-27614D02*
D03*
Y-45614D02*
D03*
D75*
X572698Y-36614D02*
D03*
D76*
X166178Y-135679D02*
D03*
X164209Y-117471D02*
D03*
Y-135679D02*
D03*
X162241D02*
D03*
X160272D02*
D03*
Y-117471D02*
D03*
X162241D02*
D03*
X166178D02*
D03*
D77*
X169377Y-135433D02*
D03*
Y-119685D02*
D03*
Y-117717D02*
D03*
Y-121653D02*
D03*
Y-123622D02*
D03*
Y-125591D02*
D03*
Y-127559D02*
D03*
Y-129528D02*
D03*
Y-131496D02*
D03*
Y-133465D02*
D03*
X157073Y-135433D02*
D03*
Y-133465D02*
D03*
Y-131496D02*
D03*
Y-129528D02*
D03*
Y-127559D02*
D03*
Y-125591D02*
D03*
Y-123622D02*
D03*
Y-121653D02*
D03*
Y-119685D02*
D03*
Y-117717D02*
D03*
D78*
X105282Y-19291D02*
D03*
D79*
X97408D02*
D03*
D80*
Y-10197D02*
D03*
D81*
X103943D02*
D03*
D82*
X107132D02*
D03*
D83*
X110958Y-7480D02*
D03*
Y-10630D02*
D03*
Y-13780D02*
D03*
Y-16929D02*
D03*
Y-20079D02*
D03*
X90158D02*
D03*
Y-16929D02*
D03*
Y-13780D02*
D03*
Y-10630D02*
D03*
Y-7480D02*
D03*
X411647Y-122343D02*
D03*
Y-119193D02*
D03*
Y-116043D02*
D03*
Y-112894D02*
D03*
Y-109744D02*
D03*
X432447D02*
D03*
Y-112894D02*
D03*
Y-116043D02*
D03*
Y-119193D02*
D03*
Y-122343D02*
D03*
D84*
X106857Y-24180D02*
D03*
X103707D02*
D03*
X100557D02*
D03*
X97408D02*
D03*
X94258D02*
D03*
Y-3379D02*
D03*
X97408D02*
D03*
X100557D02*
D03*
X103707D02*
D03*
X106857D02*
D03*
X428346Y-126443D02*
D03*
X425197D02*
D03*
X422047D02*
D03*
X418898D02*
D03*
X415748D02*
D03*
Y-105643D02*
D03*
X418898D02*
D03*
X422047D02*
D03*
X425197D02*
D03*
X428346D02*
D03*
D85*
X453937Y-136181D02*
D03*
Y-159882D02*
D03*
X457480Y-90118D02*
D03*
Y-113819D02*
D03*
D86*
X356750Y-119882D02*
D03*
X352982D02*
D03*
D87*
X390654Y-113429D02*
D03*
Y-110551D02*
D03*
X14173Y-299864D02*
D03*
Y-296986D02*
D03*
D88*
X353029Y-113189D02*
D03*
X356703D02*
D03*
D89*
X383268Y-114567D02*
D03*
Y-109055D02*
D03*
X148425Y-104336D02*
D03*
Y-98824D02*
D03*
D90*
X428300Y-192653D02*
D03*
X424560Y-201048D02*
D03*
X432040D02*
D03*
X424560Y-192653D02*
D03*
D91*
X432040D02*
D03*
D92*
X373083Y-155512D02*
D03*
X378083D02*
D03*
X388083Y-134252D02*
D03*
X383083D02*
D03*
X378083D02*
D03*
X373083D02*
D03*
X383083Y-155512D02*
D03*
X388083D02*
D03*
X613406Y-83465D02*
D03*
X608405D02*
D03*
X598406Y-62205D02*
D03*
X603406D02*
D03*
X608405D02*
D03*
X613406D02*
D03*
X603406Y-83465D02*
D03*
X598406D02*
D03*
D93*
X399410Y-120866D02*
D03*
X388976D02*
D03*
X77067Y-40157D02*
D03*
X87500D02*
D03*
X589764Y-52362D02*
D03*
X600197D02*
D03*
D94*
X66102Y-43355D02*
D03*
X44842Y-58355D02*
D03*
Y-53355D02*
D03*
X66102Y-48355D02*
D03*
Y-53355D02*
D03*
Y-58355D02*
D03*
X44842Y-48355D02*
D03*
Y-43355D02*
D03*
D95*
X25686Y-18898D02*
D03*
X35731D02*
D03*
X464961Y-125197D02*
D03*
X454915D02*
D03*
X25686Y-9843D02*
D03*
X35731D02*
D03*
D96*
X416535Y-120768D02*
D03*
D97*
Y-112894D02*
D03*
D98*
X425630D02*
D03*
D99*
Y-119429D02*
D03*
D100*
Y-122618D02*
D03*
D101*
X443307Y-112300D02*
D03*
Y-122346D02*
D03*
D102*
X362402Y-111811D02*
D03*
X375394D02*
D03*
X74616Y-61723D02*
D03*
X87608D02*
D03*
D103*
X334646Y-153937D02*
D03*
X358268D02*
D03*
D104*
X103543Y-61811D02*
D03*
Y-38189D02*
D03*
D105*
X93299Y-99606D02*
D03*
X97253D02*
D03*
X471662Y-76378D02*
D03*
X467708D02*
D03*
D106*
X386319Y-217717D02*
D03*
X382972D02*
D03*
X131004Y-348031D02*
D03*
X134350D02*
D03*
X131004Y-352362D02*
D03*
X134350D02*
D03*
X18799Y-350000D02*
D03*
X22146D02*
D03*
X3445Y-234646D02*
D03*
X6791D02*
D03*
X23524Y-239370D02*
D03*
X26870D02*
D03*
X23130Y-192520D02*
D03*
X26476D02*
D03*
X405807Y-233071D02*
D03*
X409154D02*
D03*
X405413Y-238189D02*
D03*
X408760D02*
D03*
X404626Y-219685D02*
D03*
X407972D02*
D03*
X404626Y-224016D02*
D03*
X407972D02*
D03*
X374902Y-217717D02*
D03*
X371555D02*
D03*
D107*
X387509Y-173797D02*
D03*
X334360Y-189741D02*
D03*
X387509D02*
D03*
X389478D02*
D03*
Y-173797D02*
D03*
X379635D02*
D03*
X369793D02*
D03*
X359950D02*
D03*
X350108D02*
D03*
X340265D02*
D03*
X330423D02*
D03*
X320580D02*
D03*
X379635Y-189741D02*
D03*
X369793D02*
D03*
X359950D02*
D03*
X350108D02*
D03*
X340265D02*
D03*
X330423D02*
D03*
X320580D02*
D03*
X385541D02*
D03*
Y-173797D02*
D03*
X332391Y-189741D02*
D03*
X352076Y-173797D02*
D03*
X328454Y-189741D02*
D03*
X312706Y-173797D02*
D03*
X322549Y-189741D02*
D03*
X312706D02*
D03*
X318612D02*
D03*
X357982Y-173797D02*
D03*
X344202D02*
D03*
X314675D02*
D03*
X316643Y-189741D02*
D03*
X356013Y-173797D02*
D03*
X322549D02*
D03*
X328454D02*
D03*
X318612D02*
D03*
X354045D02*
D03*
X342234D02*
D03*
X334360D02*
D03*
X324517D02*
D03*
X314675Y-189741D02*
D03*
X316643Y-173797D02*
D03*
X324517Y-189741D02*
D03*
X363887Y-173797D02*
D03*
X361919D02*
D03*
X326486D02*
D03*
X332391D02*
D03*
X338297Y-189741D02*
D03*
X336328D02*
D03*
X375698Y-173797D02*
D03*
X352076Y-189741D02*
D03*
X356013D02*
D03*
X381604Y-173797D02*
D03*
X346171Y-189741D02*
D03*
X361919D02*
D03*
X365856D02*
D03*
X373730D02*
D03*
X377667Y-173797D02*
D03*
X367824D02*
D03*
X348139Y-189741D02*
D03*
X326486D02*
D03*
X381604D02*
D03*
X383572Y-173797D02*
D03*
X371761D02*
D03*
X365856D02*
D03*
X373730D02*
D03*
X357982Y-189741D02*
D03*
X354045D02*
D03*
X375698D02*
D03*
X363887D02*
D03*
X383572D02*
D03*
X367824D02*
D03*
X342234D02*
D03*
X344202D02*
D03*
X338297Y-173797D02*
D03*
X336328D02*
D03*
X348139D02*
D03*
X346171D02*
D03*
X371761Y-189741D02*
D03*
X377667D02*
D03*
X357972Y-321918D02*
D03*
X359940D02*
D03*
X334350D02*
D03*
X318602D02*
D03*
X330413D02*
D03*
X338287D02*
D03*
X326476D02*
D03*
X348129D02*
D03*
X344192D02*
D03*
X328444Y-337862D02*
D03*
X336318D02*
D03*
X330413D02*
D03*
X318602D02*
D03*
X320570Y-321918D02*
D03*
X324507D02*
D03*
X375688D02*
D03*
X354035D02*
D03*
X334350Y-337862D02*
D03*
X324507D02*
D03*
X328444Y-321918D02*
D03*
X336318D02*
D03*
X340255D02*
D03*
X356003D02*
D03*
X320570Y-337862D02*
D03*
X346161Y-321918D02*
D03*
X350098D02*
D03*
X326476Y-337862D02*
D03*
X365846Y-321918D02*
D03*
X363877D02*
D03*
X369783Y-337862D02*
D03*
X375688D02*
D03*
X340255D02*
D03*
X338287D02*
D03*
X377657Y-321918D02*
D03*
X385531Y-337862D02*
D03*
X387499Y-321918D02*
D03*
X363877Y-337862D02*
D03*
X377657D02*
D03*
X367814D02*
D03*
X365846D02*
D03*
X359940D02*
D03*
X348129D02*
D03*
X354035D02*
D03*
X383562D02*
D03*
X373720D02*
D03*
X379625D02*
D03*
X346161D02*
D03*
X385531Y-321918D02*
D03*
X387499Y-337862D02*
D03*
X357972D02*
D03*
X344192D02*
D03*
X383562Y-321918D02*
D03*
X389468D02*
D03*
X379625D02*
D03*
X389468Y-337862D02*
D03*
X373720Y-321918D02*
D03*
X350098Y-337862D02*
D03*
X356003D02*
D03*
X369783Y-321918D02*
D03*
X316633Y-337862D02*
D03*
Y-321918D02*
D03*
X381594D02*
D03*
X371751D02*
D03*
X361909D02*
D03*
X352066D02*
D03*
X342224D02*
D03*
X332381D02*
D03*
X322539D02*
D03*
X381594Y-337862D02*
D03*
X371751D02*
D03*
X361909D02*
D03*
X352066D02*
D03*
X342224D02*
D03*
X332381D02*
D03*
X322539D02*
D03*
X312696D02*
D03*
Y-321918D02*
D03*
X314665D02*
D03*
X367814D02*
D03*
X314665Y-337862D02*
D03*
D108*
X395083Y-181814D02*
D03*
X307091D02*
D03*
X395083Y-329845D02*
D03*
X307091D02*
D03*
D109*
X238209Y-113386D02*
D03*
X233209D02*
D03*
X228209D02*
D03*
X223209D02*
D03*
X238209Y-132283D02*
D03*
X233209D02*
D03*
X228209D02*
D03*
X223209D02*
D03*
D110*
X214193Y-112795D02*
D03*
X209193D02*
D03*
X204193D02*
D03*
X199193D02*
D03*
X214193Y-131299D02*
D03*
X209193D02*
D03*
X204193D02*
D03*
X199193D02*
D03*
D111*
X182516Y-128347D02*
D03*
Y-118504D02*
D03*
D112*
X189209Y-127323D02*
D03*
Y-131339D02*
D03*
Y-117480D02*
D03*
Y-121496D02*
D03*
D113*
X168110Y-100132D02*
D03*
Y-103805D02*
D03*
D114*
X560778Y-328917D02*
D03*
X545030D02*
D03*
X552904D02*
D03*
X537156D02*
D03*
X560778Y-311417D02*
D03*
X552904D02*
D03*
X545030D02*
D03*
X537156D02*
D03*
X513534D02*
D03*
X521408D02*
D03*
X529282D02*
D03*
X537156D02*
D03*
X513534Y-328917D02*
D03*
X521408D02*
D03*
X529282D02*
D03*
X505660D02*
D03*
X560778D02*
D03*
X545030D02*
D03*
X552904D02*
D03*
X537156D02*
D03*
X560778Y-311417D02*
D03*
X552904D02*
D03*
X545030D02*
D03*
X505660D02*
D03*
D115*
X428390Y-355832D02*
D03*
X419531Y-358391D02*
D03*
Y-353273D02*
D03*
X473173Y-356620D02*
D03*
X464315Y-359179D02*
D03*
Y-354061D02*
D03*
X511594Y-356296D02*
D03*
X502736Y-358855D02*
D03*
Y-353737D02*
D03*
X556575Y-356099D02*
D03*
X547717Y-358659D02*
D03*
Y-353540D02*
D03*
D116*
X481441Y-356620D02*
D03*
X489315D02*
D03*
X436953Y-355832D02*
D03*
X444827D02*
D03*
X521339Y-356296D02*
D03*
X529213D02*
D03*
X565827Y-356690D02*
D03*
X573701D02*
D03*
D117*
X13973Y-210630D02*
D03*
Y-262795D02*
D03*
X13973Y-157332D02*
D03*
X13973Y-316929D02*
D03*
D118*
X19976Y-216437D02*
D03*
Y-204823D02*
D03*
Y-256988D02*
D03*
Y-268602D02*
D03*
X19976Y-151525D02*
D03*
Y-163139D02*
D03*
X19976Y-311122D02*
D03*
Y-322736D02*
D03*
D119*
X-1181Y-349311D02*
D03*
Y-345965D02*
D03*
X390945Y-249114D02*
D03*
Y-252461D02*
D03*
X386614Y-249114D02*
D03*
Y-252461D02*
D03*
X401575Y-249114D02*
D03*
Y-252461D02*
D03*
X396850Y-249114D02*
D03*
Y-252461D02*
D03*
D120*
X8403Y-237795D02*
D03*
X11282D02*
D03*
X5647Y-349213D02*
D03*
X8526D02*
D03*
X10372Y-193307D02*
D03*
X13250D02*
D03*
X616006Y-302756D02*
D03*
X613128D02*
D03*
D121*
X-4724Y-178543D02*
D03*
X2756D02*
D03*
Y-187205D02*
D03*
X2756Y-291732D02*
D03*
Y-283071D02*
D03*
X-4724D02*
D03*
D122*
X-3937Y-187205D02*
D03*
X-3937Y-291732D02*
D03*
D123*
X622047Y-343307D02*
D03*
Y-333307D02*
D03*
Y-323307D02*
D03*
Y-313307D02*
D03*
Y-353307D02*
D03*
X602559D02*
D03*
Y-343307D02*
D03*
Y-333307D02*
D03*
Y-323307D02*
D03*
Y-313307D02*
D03*
D124*
X153150Y-103459D02*
D03*
Y-99691D02*
D03*
D125*
X127981Y-132385D02*
D03*
X130540D02*
D03*
X127981Y-124314D02*
D03*
X130540D02*
D03*
X133099D02*
D03*
X135658D02*
D03*
Y-132385D02*
D03*
X133099D02*
D03*
D126*
X-18406Y-176772D02*
D03*
Y-187795D02*
D03*
Y-59646D02*
D03*
Y-70669D02*
D03*
Y-240551D02*
D03*
Y-229528D02*
D03*
Y-294094D02*
D03*
Y-283071D02*
D03*
Y-346850D02*
D03*
Y-335827D02*
D03*
Y-113976D02*
D03*
Y-102953D02*
D03*
D127*
X-19685Y-180512D02*
D03*
Y-184055D02*
D03*
Y-63386D02*
D03*
Y-66929D02*
D03*
Y-236811D02*
D03*
Y-233268D02*
D03*
Y-290354D02*
D03*
Y-286811D02*
D03*
Y-343110D02*
D03*
Y-339567D02*
D03*
Y-110236D02*
D03*
Y-106693D02*
D03*
D128*
X612648Y-256693D02*
D03*
X608612D02*
D03*
D129*
X610827Y-235433D02*
D03*
X612598D02*
D03*
X614370D02*
D03*
X616142D02*
D03*
X617913D02*
D03*
X619685D02*
D03*
Y-246579D02*
D03*
X617913D02*
D03*
X616142D02*
D03*
X614370D02*
D03*
X612598D02*
D03*
D130*
X610827D02*
D03*
D131*
X605418Y-300000D02*
D03*
X599307D02*
D03*
D132*
X596063Y-292126D02*
D03*
X600000D02*
D03*
X608661Y-261024D02*
D03*
X612598D02*
D03*
D133*
X550787Y-64567D02*
D03*
X576772D02*
D03*
D134*
X261126Y-299333D02*
D03*
Y-211341D02*
D03*
X448528D02*
D03*
Y-299333D02*
D03*
D135*
X269054Y-262222D02*
D03*
Y-264190D02*
D03*
Y-238600D02*
D03*
Y-222852D02*
D03*
Y-234663D02*
D03*
Y-242537D02*
D03*
Y-230726D02*
D03*
Y-252379D02*
D03*
Y-248442D02*
D03*
X253110Y-232694D02*
D03*
Y-240568D02*
D03*
Y-234663D02*
D03*
Y-222852D02*
D03*
X269054Y-224820D02*
D03*
Y-228757D02*
D03*
Y-279938D02*
D03*
Y-258285D02*
D03*
X253110Y-238600D02*
D03*
Y-228757D02*
D03*
X269054Y-232694D02*
D03*
Y-240568D02*
D03*
Y-244505D02*
D03*
Y-260253D02*
D03*
X253110Y-224820D02*
D03*
X269054Y-250411D02*
D03*
Y-254348D02*
D03*
X253110Y-230726D02*
D03*
X269054Y-270096D02*
D03*
Y-268127D02*
D03*
X253110Y-274033D02*
D03*
Y-279938D02*
D03*
Y-244505D02*
D03*
Y-242537D02*
D03*
X269054Y-281907D02*
D03*
X253110Y-289781D02*
D03*
X269054Y-291749D02*
D03*
X253110Y-268127D02*
D03*
Y-281907D02*
D03*
Y-272064D02*
D03*
Y-270096D02*
D03*
Y-264190D02*
D03*
Y-252379D02*
D03*
Y-258285D02*
D03*
Y-287812D02*
D03*
Y-277970D02*
D03*
Y-283875D02*
D03*
Y-250411D02*
D03*
X269054Y-289781D02*
D03*
X253110Y-291749D02*
D03*
Y-262222D02*
D03*
Y-248442D02*
D03*
X269054Y-287812D02*
D03*
Y-293718D02*
D03*
Y-283875D02*
D03*
X253110Y-293718D02*
D03*
X269054Y-277970D02*
D03*
X253110Y-254348D02*
D03*
Y-260253D02*
D03*
X269054Y-274033D02*
D03*
X253110Y-220883D02*
D03*
X269054D02*
D03*
Y-285844D02*
D03*
Y-276001D02*
D03*
Y-266159D02*
D03*
Y-256316D02*
D03*
Y-246474D02*
D03*
Y-236631D02*
D03*
Y-226789D02*
D03*
X253110Y-285844D02*
D03*
Y-276001D02*
D03*
Y-266159D02*
D03*
Y-256316D02*
D03*
Y-246474D02*
D03*
Y-236631D02*
D03*
Y-226789D02*
D03*
Y-216946D02*
D03*
X269054D02*
D03*
Y-218915D02*
D03*
Y-272064D02*
D03*
X253110Y-218915D02*
D03*
X440601Y-248452D02*
D03*
Y-246484D02*
D03*
Y-272074D02*
D03*
Y-287822D02*
D03*
Y-276011D02*
D03*
Y-268137D02*
D03*
Y-279948D02*
D03*
Y-258295D02*
D03*
Y-262232D02*
D03*
X456545Y-277980D02*
D03*
Y-270106D02*
D03*
Y-276011D02*
D03*
Y-287822D02*
D03*
X440601Y-285854D02*
D03*
Y-281917D02*
D03*
Y-230736D02*
D03*
Y-252389D02*
D03*
X456545Y-272074D02*
D03*
Y-281917D02*
D03*
X440601Y-277980D02*
D03*
Y-270106D02*
D03*
Y-266169D02*
D03*
Y-250421D02*
D03*
X456545Y-285854D02*
D03*
X440601Y-260263D02*
D03*
Y-256326D02*
D03*
X456545Y-279948D02*
D03*
X440601Y-240578D02*
D03*
Y-242547D02*
D03*
X456545Y-236641D02*
D03*
Y-230736D02*
D03*
Y-266169D02*
D03*
Y-268137D02*
D03*
X440601Y-228767D02*
D03*
X456545Y-220893D02*
D03*
X440601Y-218925D02*
D03*
X456545Y-242547D02*
D03*
Y-228767D02*
D03*
Y-238610D02*
D03*
Y-240578D02*
D03*
Y-246484D02*
D03*
Y-258295D02*
D03*
Y-252389D02*
D03*
Y-222862D02*
D03*
Y-232704D02*
D03*
Y-226799D02*
D03*
Y-260263D02*
D03*
X440601Y-220893D02*
D03*
X456545Y-218925D02*
D03*
Y-248452D02*
D03*
Y-262232D02*
D03*
X440601Y-222862D02*
D03*
Y-216956D02*
D03*
Y-226799D02*
D03*
X456545Y-216956D02*
D03*
X440601Y-232704D02*
D03*
X456545Y-256326D02*
D03*
Y-250421D02*
D03*
X440601Y-236641D02*
D03*
X456545Y-289791D02*
D03*
X440601D02*
D03*
Y-224830D02*
D03*
Y-234673D02*
D03*
Y-244515D02*
D03*
Y-254358D02*
D03*
Y-264200D02*
D03*
Y-274043D02*
D03*
Y-283885D02*
D03*
X456545Y-224830D02*
D03*
Y-234673D02*
D03*
Y-244515D02*
D03*
Y-254358D02*
D03*
Y-264200D02*
D03*
Y-274043D02*
D03*
Y-283885D02*
D03*
Y-293728D02*
D03*
X440601D02*
D03*
Y-291759D02*
D03*
Y-238610D02*
D03*
X456545Y-291759D02*
D03*
D136*
X209193Y-252680D02*
D03*
X224941D02*
D03*
X209193Y-250680D02*
D03*
X224941D02*
D03*
X209193Y-248680D02*
D03*
X224941D02*
D03*
X209193Y-246680D02*
D03*
X224941D02*
D03*
X209193Y-244680D02*
D03*
X224941D02*
D03*
X209193Y-242680D02*
D03*
X224941D02*
D03*
X209193Y-240680D02*
D03*
X224941D02*
D03*
X209193Y-238680D02*
D03*
X224941D02*
D03*
X209193Y-236680D02*
D03*
X224941D02*
D03*
Y-234680D02*
D03*
X209193D02*
D03*
Y-252680D02*
D03*
X224941D02*
D03*
X209193Y-250680D02*
D03*
X224941D02*
D03*
X209193Y-248680D02*
D03*
X224941D02*
D03*
X209193Y-246680D02*
D03*
X224941D02*
D03*
X209193Y-244680D02*
D03*
X224941D02*
D03*
X209193Y-242680D02*
D03*
X224941D02*
D03*
X209193Y-240680D02*
D03*
X224941D02*
D03*
X209193Y-238680D02*
D03*
X224941D02*
D03*
X209193Y-236680D02*
D03*
X224941D02*
D03*
Y-234680D02*
D03*
X209193D02*
D03*
D137*
X599213Y-28445D02*
D03*
Y-40059D02*
D03*
D138*
X27067Y-234842D02*
D03*
Y-232874D02*
D03*
Y-230906D02*
D03*
Y-228937D02*
D03*
X14665D02*
D03*
Y-230906D02*
D03*
Y-232874D02*
D03*
Y-234842D02*
D03*
X27067Y-187205D02*
D03*
Y-185236D02*
D03*
Y-183268D02*
D03*
Y-181299D02*
D03*
X14665D02*
D03*
Y-183268D02*
D03*
Y-185236D02*
D03*
Y-187205D02*
D03*
X27067Y-291929D02*
D03*
Y-289961D02*
D03*
Y-287992D02*
D03*
Y-286024D02*
D03*
X14665D02*
D03*
Y-287992D02*
D03*
Y-289961D02*
D03*
Y-291929D02*
D03*
X21949Y-344685D02*
D03*
Y-342717D02*
D03*
Y-340748D02*
D03*
Y-338779D02*
D03*
X9547D02*
D03*
Y-340748D02*
D03*
Y-342717D02*
D03*
Y-344685D02*
D03*
D139*
X1181Y-340945D02*
D03*
Y-335433D02*
D03*
X11417Y-225984D02*
D03*
Y-220472D02*
D03*
D140*
X14567Y-280709D02*
D03*
X9055D02*
D03*
X10236Y-175591D02*
D03*
X15748D02*
D03*
D141*
X281102Y-401427D02*
D03*
X159055D02*
D03*
X155118D02*
D03*
X151181D02*
D03*
X178740D02*
D03*
X222047D02*
D03*
X265354D02*
D03*
X261417D02*
D03*
X249606D02*
D03*
X245669D02*
D03*
X233858D02*
D03*
X229921D02*
D03*
X214173D02*
D03*
X210236D02*
D03*
X186614D02*
D03*
X182677D02*
D03*
X202362D02*
D03*
X273228D02*
D03*
X166929D02*
D03*
X170866D02*
D03*
X190551D02*
D03*
X269291D02*
D03*
X257480D02*
D03*
X241732D02*
D03*
X237795D02*
D03*
X174803D02*
D03*
X162992D02*
D03*
X253543D02*
D03*
X206299D02*
D03*
X218110D02*
D03*
X225984D02*
D03*
D142*
X277165Y-399477D02*
D03*
D143*
X590551Y-35472D02*
D03*
Y-40905D02*
D03*
D144*
X620079Y-266682D02*
D03*
X620078Y-293357D02*
D03*
D169*
X482874Y-262598D02*
D03*
Y-264173D02*
D03*
Y-265748D02*
D03*
Y-267323D02*
D03*
Y-268898D02*
D03*
X477756D02*
D03*
Y-267323D02*
D03*
Y-265748D02*
D03*
Y-264173D02*
D03*
X328150Y-236614D02*
D03*
Y-238189D02*
D03*
Y-239764D02*
D03*
Y-241339D02*
D03*
Y-242913D02*
D03*
X323031D02*
D03*
Y-241339D02*
D03*
Y-239764D02*
D03*
Y-238189D02*
D03*
X341929Y-289764D02*
D03*
Y-291339D02*
D03*
Y-292913D02*
D03*
Y-294488D02*
D03*
Y-296063D02*
D03*
X336811D02*
D03*
Y-294488D02*
D03*
Y-292913D02*
D03*
Y-291339D02*
D03*
X323031Y-290551D02*
D03*
Y-292126D02*
D03*
Y-293701D02*
D03*
Y-295276D02*
D03*
Y-296850D02*
D03*
X317913D02*
D03*
Y-295276D02*
D03*
Y-293701D02*
D03*
Y-292126D02*
D03*
D170*
X480315Y-268898D02*
D03*
Y-262598D02*
D03*
X325590Y-242913D02*
D03*
Y-236614D02*
D03*
X339370Y-296063D02*
D03*
Y-289764D02*
D03*
X320472Y-296850D02*
D03*
Y-290551D02*
D03*
D171*
X478543Y-262598D02*
D03*
X186614Y-96260D02*
D03*
X278740Y-197047D02*
D03*
X323819Y-236614D02*
D03*
X337598Y-289764D02*
D03*
X318701Y-290551D02*
D03*
D174*
X186614Y-91929D02*
D03*
X188189D02*
D03*
X189764D02*
D03*
X191339D02*
D03*
X192913D02*
D03*
Y-97047D02*
D03*
X191339D02*
D03*
X189764D02*
D03*
X188189D02*
D03*
X280315Y-197835D02*
D03*
X281890D02*
D03*
X283465D02*
D03*
X285039D02*
D03*
Y-192717D02*
D03*
X283465D02*
D03*
X281890D02*
D03*
X280315D02*
D03*
X278740D02*
D03*
D175*
X192913Y-94488D02*
D03*
X186614D02*
D03*
X278740Y-195276D02*
D03*
X285039D02*
D03*
D194*
X615256Y-241006D02*
D03*
D210*
X603110Y-805D02*
D03*
D211*
X574409Y7445D02*
D03*
D212*
Y-9055D02*
D03*
X552709Y7445D02*
D03*
Y-9055D02*
D03*
D216*
X225327Y-368504D02*
D03*
D217*
X321260Y-145669D02*
D03*
Y-135669D02*
D03*
Y-125669D02*
D03*
X194882Y394D02*
D03*
X496457Y-271358D02*
D03*
D218*
X194882Y-78347D02*
D03*
X575197Y-271358D02*
D03*
D230*
X386614Y-234252D02*
D03*
D231*
X139370Y-117717D02*
X140551Y-116535D01*
X139370Y-118898D02*
Y-117717D01*
X140551Y-116535D02*
X142520Y-114567D01*
Y-110462D01*
X529282Y-311417D02*
Y-300787D01*
X576575Y-297736D02*
Y-289075D01*
X134003Y-116115D02*
X134034Y-116147D01*
X134003Y-116115D02*
Y-110494D01*
X133971Y-110462D02*
X134003Y-110494D01*
X133971Y-110462D02*
X142520D01*
X253082Y-115065D02*
Y-110236D01*
X495079Y-298130D02*
Y-289075D01*
X537156Y-311417D02*
Y-300787D01*
X505660Y-311417D02*
Y-303150D01*
X168110Y1772D02*
X177165D01*
X147047Y-18159D02*
X156693D01*
X168504Y-79724D02*
X177165D01*
X147047Y-41781D02*
X157087D01*
Y-41732D01*
Y-74803D02*
Y-41781D01*
X149606Y-80315D02*
X151575D01*
X157087Y-74803D01*
X147047Y-49655D02*
X147096Y-49606D01*
X152756D01*
X567107Y-303150D02*
X569685D01*
X560778Y-311417D02*
Y-309478D01*
X567107Y-303150D01*
X30709Y-50772D02*
X30724Y-50787D01*
X35433D01*
X121467Y-73277D02*
X129547D01*
X119340Y-41781D02*
X129547D01*
X118504Y-40945D02*
X119340Y-41781D01*
X103543Y-38189D02*
X113949D01*
X624918Y-196353D02*
X624938Y-196373D01*
X624918Y-201353D02*
X624926D01*
X624918Y-206353D02*
X624938Y-206373D01*
X624430Y-173898D02*
X625079D01*
X624430Y-163898D02*
X624685D01*
X495079Y-298130D02*
X495276D01*
X576378Y-297736D02*
X576575D01*
X168504Y-79724D02*
Y-79528D01*
X168110Y1575D02*
Y1772D01*
X121467Y-74575D02*
Y-73277D01*
X560778Y-340158D02*
Y-328917D01*
X559449Y-340158D02*
X560778D01*
X536221Y-300787D02*
X537156D01*
X529282D02*
X530709D01*
X529282Y-338976D02*
Y-328917D01*
Y-338976D02*
X530315D01*
X505512Y-303150D02*
X505660D01*
X347638Y-119882D02*
X352982D01*
X347244Y-113189D02*
X353029D01*
X355035Y-105876D02*
X359929D01*
X361736Y-111146D02*
Y-107683D01*
X359929Y-105876D02*
X361736Y-107683D01*
Y-111146D02*
X362402Y-111811D01*
X598032Y-343307D02*
X602559D01*
X598172Y-333307D02*
X602559D01*
X156693Y-18159D02*
Y-18110D01*
D232*
X298031Y-155669D02*
X321260D01*
X285039Y-155512D02*
X298031D01*
D233*
X142520Y-110462D02*
Y-92913D01*
X149606Y-80315D02*
Y-73277D01*
X147047D02*
X149606D01*
Y-85827D02*
Y-80315D01*
X142520Y-92913D02*
X149606Y-85827D01*
D234*
X155526Y-370989D02*
D03*
D235*
X155364Y-388287D02*
D03*
D236*
X298031Y-115512D02*
D03*
Y-145512D02*
D03*
Y-125512D02*
D03*
Y-135512D02*
D03*
D237*
Y-155512D02*
D03*
D238*
X321260Y-155669D02*
D03*
D239*
X0Y0D02*
D03*
X0Y-378395D02*
D03*
D240*
X608268Y-288779D02*
D03*
Y-271260D02*
D03*
D241*
X620079Y-263583D02*
D03*
Y-296457D02*
D03*
D242*
X354035Y-38976D02*
D03*
X424803D02*
D03*
X535827Y-112205D02*
D03*
D243*
X390462Y-181769D02*
D03*
X311722D02*
D03*
X390452Y-329890D02*
D03*
X311712D02*
D03*
X261082Y-294702D02*
D03*
Y-215962D02*
D03*
X448573Y-215972D02*
D03*
Y-294712D02*
D03*
D244*
X186221Y-334252D02*
D03*
X198031D02*
D03*
X58268Y-163779D02*
D03*
X209842Y-334252D02*
D03*
X58268Y-323622D02*
D03*
X218110Y-163779D02*
D03*
X58268Y-243701D02*
D03*
X174221Y-334252D02*
D03*
X218110Y-323622D02*
D03*
X162221Y-334252D02*
D03*
X174221D02*
D03*
X198031D02*
D03*
X209842D02*
D03*
X218110Y-163779D02*
D03*
Y-323622D02*
D03*
X58268D02*
D03*
Y-243701D02*
D03*
Y-163779D02*
D03*
X186221Y-334252D02*
D03*
X162221D02*
D03*
D245*
X200876Y-315719D02*
D03*
X75768Y-321622D02*
D03*
X78268Y-159780D02*
D03*
X200610Y-171879D02*
D03*
D246*
X-18464Y-326781D02*
D03*
X1535D02*
D03*
Y-306781D02*
D03*
X-18464D02*
D03*
X-18465Y-273630D02*
D03*
X1535D02*
D03*
Y-253630D02*
D03*
X-18465D02*
D03*
Y-220480D02*
D03*
X1535D02*
D03*
Y-200480D02*
D03*
X-18465D02*
D03*
X-18464Y-167332D02*
D03*
X1535D02*
D03*
Y-147332D02*
D03*
X-18464D02*
D03*
D247*
X-8465Y-316781D02*
D03*
X-8465Y-263630D02*
D03*
Y-210480D02*
D03*
X-8465Y-157332D02*
D03*
D248*
X609449Y-98189D02*
D03*
D249*
Y-108189D02*
D03*
Y-118189D02*
D03*
Y-128189D02*
D03*
Y-138189D02*
D03*
Y-148189D02*
D03*
X619449Y-98189D02*
D03*
Y-108189D02*
D03*
Y-118189D02*
D03*
Y-128189D02*
D03*
Y-138189D02*
D03*
Y-148189D02*
D03*
D250*
X181534Y-387757D02*
D03*
X522047Y-270866D02*
D03*
X496620Y-310492D02*
D03*
X61811Y787D02*
D03*
X593307Y-292126D02*
D03*
X245325Y-120837D02*
D03*
X500049Y-256633D02*
D03*
X585039Y-266142D02*
D03*
X560630Y-269291D02*
D03*
X599044Y-275032D02*
D03*
X585039Y-272835D02*
D03*
X581496D02*
D03*
X548425Y-269632D02*
D03*
X541093Y-284626D02*
D03*
X541411Y-269932D02*
D03*
X536489Y-269182D02*
D03*
X554724Y-272441D02*
D03*
X555460Y-284401D02*
D03*
X574406Y-280807D02*
D03*
X567525Y-286203D02*
D03*
X581890Y-290158D02*
D03*
X583815Y-275386D02*
D03*
X614822Y-250158D02*
D03*
X604724Y-274803D02*
D03*
X321260Y-166142D02*
D03*
X323622Y-166535D02*
D03*
X150394Y-140157D02*
D03*
X317323Y-114961D02*
D03*
X321260D02*
D03*
X320761Y-183851D02*
D03*
X309449Y-211811D02*
D03*
X313386Y-212598D02*
D03*
X124016Y-110236D02*
D03*
X222351Y-98694D02*
D03*
X245276Y-115748D02*
D03*
X211648Y-103695D02*
D03*
X44001Y-137747D02*
D03*
X100729Y-127872D02*
D03*
X-23622Y-181102D02*
D03*
X98761Y-129872D02*
D03*
X57422Y-128927D02*
D03*
X89312Y-128140D02*
D03*
X84981D02*
D03*
X80651D02*
D03*
X89312Y-123809D02*
D03*
X84981D02*
D03*
X80651D02*
D03*
X89312Y-119478D02*
D03*
X84981D02*
D03*
X80651D02*
D03*
X98761Y-125872D02*
D03*
X58407Y-137589D02*
D03*
X85044Y-139557D02*
D03*
X81044D02*
D03*
X89044D02*
D03*
X71202Y-138095D02*
D03*
X79044Y-137936D02*
D03*
X83044D02*
D03*
X91044D02*
D03*
X87044D02*
D03*
X68889Y-137453D02*
D03*
X98761Y-117746D02*
D03*
Y-121871D02*
D03*
X52501Y-119872D02*
D03*
X44134Y-115080D02*
D03*
X44621Y-110628D02*
D03*
X58210Y-108061D02*
D03*
X91044Y-110061D02*
D03*
X78918Y-110029D02*
D03*
X82918D02*
D03*
X86981D02*
D03*
X80981Y-108061D02*
D03*
X88981D02*
D03*
X84981D02*
D03*
X139370Y-118898D02*
D03*
X262724Y-107813D02*
D03*
X253082Y-110236D02*
D03*
X317828Y-161260D02*
D03*
X313878Y-161597D02*
D03*
X286221Y-124803D02*
D03*
X285827Y-137795D02*
D03*
X285384Y-154492D02*
D03*
X284646Y-128347D02*
D03*
X284252Y-144095D02*
D03*
X282058Y-151217D02*
D03*
X281890Y-155905D02*
D03*
X281496Y-124409D02*
D03*
X280709Y-137795D02*
D03*
X276650Y-128810D02*
D03*
X276083Y-152559D02*
D03*
Y-141142D02*
D03*
X255906Y-126378D02*
D03*
Y-131496D02*
D03*
Y-137008D02*
D03*
Y-142126D02*
D03*
X257480Y-150394D02*
D03*
X255512Y-146850D02*
D03*
X140551Y-116535D02*
D03*
X368110Y-330315D02*
D03*
X262006Y-387255D02*
D03*
X365354Y-330315D02*
D03*
X265158Y-387253D02*
D03*
X374114Y-346144D02*
D03*
X246339Y-386975D02*
D03*
X249410Y-387253D02*
D03*
X371359Y-346144D02*
D03*
X237992Y-374655D02*
D03*
X367422Y-346144D02*
D03*
X241929Y-374655D02*
D03*
X364666Y-346144D02*
D03*
X354036D02*
D03*
X206496Y-374655D02*
D03*
X351280Y-346144D02*
D03*
X210433Y-374655D02*
D03*
X360729Y-346144D02*
D03*
X229331Y-387253D02*
D03*
X357973Y-346144D02*
D03*
X232480Y-387253D02*
D03*
X212795D02*
D03*
X215945D02*
D03*
X356299Y-330315D02*
D03*
X353543D02*
D03*
X218445Y-374108D02*
D03*
X222638Y-374655D02*
D03*
X364567Y-326378D02*
D03*
X357575Y-327776D02*
D03*
X357480Y-332677D02*
D03*
X350787Y-329921D02*
D03*
X359652Y-326841D02*
D03*
X362408D02*
D03*
X205906Y-372441D02*
D03*
X211024D02*
D03*
X222835Y-372047D02*
D03*
X217323Y-371654D02*
D03*
X237795D02*
D03*
X242897Y-371864D02*
D03*
X250394Y-375984D02*
D03*
X259449Y-373228D02*
D03*
X268504Y-372047D02*
D03*
X274803Y-372441D02*
D03*
X266929Y-385039D02*
D03*
X243701Y-389370D02*
D03*
X250394Y-384646D02*
D03*
X227953Y-383858D02*
D03*
X233858Y-384646D02*
D03*
X213386D02*
D03*
X513386Y-199213D02*
D03*
X521654Y-198819D02*
D03*
X591339Y-189764D02*
D03*
X153225Y-121747D02*
D03*
X133099Y-136519D02*
D03*
X24500Y-8429D02*
D03*
X603150Y-235946D02*
D03*
X604316Y-246600D02*
D03*
X152756Y-65354D02*
D03*
Y-57480D02*
D03*
Y-49606D02*
D03*
X157480Y-73228D02*
D03*
X284646Y-291732D02*
D03*
X381890Y-183858D02*
D03*
X384646Y-184252D02*
D03*
X359842Y-161024D02*
D03*
X363386Y-160630D02*
D03*
X367717D02*
D03*
X454775Y-308565D02*
D03*
X569685Y-303150D02*
D03*
X608268Y-84252D02*
D03*
X383083Y-161839D02*
D03*
X421313Y-174784D02*
D03*
X396850Y-249016D02*
D03*
X129063Y-136618D02*
D03*
X38613Y-53355D02*
D03*
X172674Y-138386D02*
D03*
X613406Y-89494D02*
D03*
X388189Y-162205D02*
D03*
X419798Y-176745D02*
D03*
X401575Y-249213D02*
D03*
X126307Y-136224D02*
D03*
X38583Y-58355D02*
D03*
X170311Y-139961D02*
D03*
X491732Y-149213D02*
D03*
X500394Y-145669D02*
D03*
X496063Y-145276D02*
D03*
X491732D02*
D03*
X550391Y-243310D02*
D03*
X477165Y-247244D02*
D03*
X539370Y-228740D02*
D03*
X542913D02*
D03*
X561024Y-183465D02*
D03*
Y-186614D02*
D03*
X-4724Y-283071D02*
D03*
X35433Y-129528D02*
D03*
X32283D02*
D03*
X28740D02*
D03*
X35433Y-50787D02*
D03*
X149935Y-124206D02*
D03*
X150233Y-119882D02*
D03*
X429528Y-231496D02*
D03*
X364173Y-280315D02*
D03*
X462205Y-255118D02*
D03*
X464961Y-125197D02*
D03*
X50000Y-44094D02*
D03*
X324016Y-42913D02*
D03*
X318898Y-43307D02*
D03*
X324016Y-39764D02*
D03*
X318898D02*
D03*
X324016Y-35827D02*
D03*
X318898D02*
D03*
X505118Y-24016D02*
D03*
X500787Y-24409D02*
D03*
X496457Y-24016D02*
D03*
X505118Y-20079D02*
D03*
X500787D02*
D03*
X496457D02*
D03*
X245669Y-74016D02*
D03*
X246063Y-70079D02*
D03*
X241732Y-74016D02*
D03*
Y-70079D02*
D03*
X326772Y-73622D02*
D03*
X322441D02*
D03*
X317717Y-73228D02*
D03*
X326772Y-69291D02*
D03*
X322441D02*
D03*
X317717D02*
D03*
X427953Y-206299D02*
D03*
X481496Y-197244D02*
D03*
X468504Y-44488D02*
D03*
X463779D02*
D03*
X458661Y-44094D02*
D03*
X468898Y-39764D02*
D03*
X463779Y-39370D02*
D03*
X458661D02*
D03*
X295669Y-45276D02*
D03*
X290945D02*
D03*
X295276Y-40945D02*
D03*
X290945D02*
D03*
X295276Y-35433D02*
D03*
X290945D02*
D03*
X118504Y-40945D02*
D03*
X85039Y-77559D02*
D03*
X383465Y-234252D02*
D03*
X389764D02*
D03*
X386614Y-237402D02*
D03*
Y-231102D02*
D03*
X611811Y-221260D02*
D03*
X426772Y-179528D02*
D03*
X418898Y-245276D02*
D03*
X602105Y-99109D02*
D03*
X597244Y-108661D02*
D03*
X592913Y-116535D02*
D03*
X594488Y-132677D02*
D03*
X43701Y-34646D02*
D03*
X51287Y-126878D02*
D03*
X13386D02*
D03*
X29543Y-345214D02*
D03*
X240158Y-278740D02*
D03*
X26378Y-20472D02*
D03*
X24409Y-16535D02*
D03*
X26378Y-10630D02*
D03*
X35433Y15354D02*
D03*
X36220Y8268D02*
D03*
X35827Y1575D02*
D03*
X19685Y-2362D02*
D03*
X20079Y3937D02*
D03*
Y10630D02*
D03*
Y17323D02*
D03*
X298819Y-269685D02*
D03*
X391339Y-277953D02*
D03*
X299606Y-185433D02*
D03*
X231102Y-239764D02*
D03*
X230709Y-242913D02*
D03*
X399213Y-193307D02*
D03*
X204331Y-101575D02*
D03*
X432283Y-254724D02*
D03*
X496063Y-244094D02*
D03*
X173228Y-117323D02*
D03*
X261024Y-200394D02*
D03*
X381890Y-254331D02*
D03*
X318989Y-253024D02*
D03*
X337402Y-260630D02*
D03*
X429134Y-246850D02*
D03*
X483831Y-241339D02*
D03*
X488189Y-216535D02*
D03*
X500971Y-219896D02*
D03*
X470472Y-246457D02*
D03*
X476968Y-76378D02*
D03*
X462992D02*
D03*
X289370Y-205906D02*
D03*
X343701Y-200394D02*
D03*
X357480Y-214567D02*
D03*
X153150Y-113386D02*
D03*
X226378Y-32677D02*
D03*
X100394Y-30315D02*
D03*
X383071Y-276772D02*
D03*
X402756Y-281102D02*
D03*
X616929Y-225984D02*
D03*
X611614Y-186107D02*
D03*
X586221Y-178740D02*
D03*
X591339Y-144488D02*
D03*
X586614Y-158661D02*
D03*
X582165Y-163898D02*
D03*
X581890Y-174016D02*
D03*
X579134Y-214006D02*
D03*
X581890Y-235925D02*
D03*
X584646Y-225197D02*
D03*
X590188Y-221161D02*
D03*
X608661Y-220472D02*
D03*
X589370Y-212992D02*
D03*
X588922Y-206462D02*
D03*
X583858Y-192913D02*
D03*
X589370Y-201575D02*
D03*
X329528Y-181890D02*
D03*
X307087Y-198819D02*
D03*
X279134Y-230315D02*
D03*
X280315Y-226378D02*
D03*
X277165Y-236221D02*
D03*
X281496Y-237402D02*
D03*
X27559Y-337402D02*
D03*
X288583Y-237402D02*
D03*
X293307Y-237008D02*
D03*
X341339Y-277953D02*
D03*
X407874Y-216535D02*
D03*
X408760Y-238189D02*
D03*
X462473Y-277635D02*
D03*
X321850Y-283465D02*
D03*
X461417Y-305118D02*
D03*
X343701Y-209449D02*
D03*
X347638Y-202756D02*
D03*
X383071Y-168110D02*
D03*
X598397Y-88288D02*
D03*
X603543Y-87795D02*
D03*
X135433Y-79134D02*
D03*
X424409Y-205512D02*
D03*
X428346Y-187795D02*
D03*
X140070Y-132385D02*
D03*
X140116Y-124048D02*
D03*
X141339Y394D02*
D03*
X180610Y-87795D02*
D03*
X198524D02*
D03*
X197244Y-102756D02*
D03*
X181004Y-101181D02*
D03*
X177559Y-87795D02*
D03*
X197638Y-97638D02*
D03*
X182283Y-97244D02*
D03*
X182677Y-94488D02*
D03*
X189764Y-88189D02*
D03*
Y-100787D02*
D03*
X196850Y-94488D02*
D03*
X161417Y-25984D02*
D03*
X169291Y13386D02*
D03*
Y9646D02*
D03*
X159843D02*
D03*
X151181Y14173D02*
D03*
X142520Y13189D02*
D03*
X144685Y-11811D02*
D03*
X162598Y-9449D02*
D03*
X153543Y-10433D02*
D03*
X162598Y-13189D02*
D03*
Y-1575D02*
D03*
X151181Y18110D02*
D03*
X137598Y-6299D02*
D03*
X134055D02*
D03*
X149803Y-9238D02*
D03*
X150000Y-787D02*
D03*
X151782Y10443D02*
D03*
X473303Y-276476D02*
D03*
X479331Y-294626D02*
D03*
X487402Y-256988D02*
D03*
X485827Y-279429D02*
D03*
X476772Y-254035D02*
D03*
X473622Y-259055D02*
D03*
X476378Y-273622D02*
D03*
X486221Y-265748D02*
D03*
X474409D02*
D03*
X480315Y-259744D02*
D03*
Y-271752D02*
D03*
X548819Y-300787D02*
D03*
X489567Y-310236D02*
D03*
X492323Y-303543D02*
D03*
X495866D02*
D03*
X483465Y-291535D02*
D03*
X476772Y-291929D02*
D03*
X466142Y-294685D02*
D03*
Y-298228D02*
D03*
X461417Y-312099D02*
D03*
X473819Y-315354D02*
D03*
X484842Y-317717D02*
D03*
X493110Y-310236D02*
D03*
X461024Y-302756D02*
D03*
X498425Y-307087D02*
D03*
X478346Y-305118D02*
D03*
X477362Y-313767D02*
D03*
X596865Y-266396D02*
D03*
X594765D02*
D03*
X624938Y-196373D02*
D03*
X624926Y-201353D02*
D03*
X624938Y-206373D02*
D03*
X624918Y-211353D02*
D03*
X625079Y-173898D02*
D03*
X624685Y-163898D02*
D03*
X551968Y-297638D02*
D03*
X127165Y-12598D02*
D03*
X118110Y-36220D02*
D03*
X117717Y-47293D02*
D03*
X121653Y-52756D02*
D03*
Y-31496D02*
D03*
X404493Y-224149D02*
D03*
X404626Y-219685D02*
D03*
X578332Y-261235D02*
D03*
X507874Y-255906D02*
D03*
X534814Y-297190D02*
D03*
X528960Y-296841D02*
D03*
X495276Y-298130D02*
D03*
X503346Y-297967D02*
D03*
X507480Y-298130D02*
D03*
X501181D02*
D03*
X516929D02*
D03*
X522835Y-297736D02*
D03*
X540945Y-297342D02*
D03*
X546457D02*
D03*
X562205Y-297736D02*
D03*
X568110D02*
D03*
X570472D02*
D03*
X576378D02*
D03*
X571260Y-256791D02*
D03*
X568898D02*
D03*
X550000Y-255610D02*
D03*
X540945Y-256004D02*
D03*
X538976Y-250886D02*
D03*
X536614Y-245374D02*
D03*
X518110Y-255217D02*
D03*
X522047Y-249705D02*
D03*
X524016Y-243799D02*
D03*
X502362Y-257185D02*
D03*
X504331D02*
D03*
X513386Y-254429D02*
D03*
X508268Y-251673D02*
D03*
X564173Y-255906D02*
D03*
X494882Y-262303D02*
D03*
X495669Y-255512D02*
D03*
X209449Y7087D02*
D03*
X203937Y1969D02*
D03*
X214173Y1181D02*
D03*
Y-79134D02*
D03*
X205118Y-79380D02*
D03*
X214567Y-11417D02*
D03*
X211811Y-16535D02*
D03*
X209055Y-7480D02*
D03*
Y-5512D02*
D03*
X209449Y-3543D02*
D03*
X216535Y-25197D02*
D03*
X211024Y-21260D02*
D03*
X220866Y-39764D02*
D03*
X215354Y-42126D02*
D03*
X210236Y-44094D02*
D03*
X210630Y-53150D02*
D03*
X209541Y-58689D02*
D03*
X209449Y-72047D02*
D03*
Y-74410D02*
D03*
X168504Y-79528D02*
D03*
Y-73622D02*
D03*
Y-71260D02*
D03*
Y-65354D02*
D03*
X168898Y-49606D02*
D03*
Y-44094D02*
D03*
X168504Y-37795D02*
D03*
Y-31890D02*
D03*
Y-25984D02*
D03*
X168110Y-20079D02*
D03*
Y-4331D02*
D03*
Y-10630D02*
D03*
X168273Y-6496D02*
D03*
X168110Y1575D02*
D03*
X101181Y-38583D02*
D03*
X144095Y-80315D02*
D03*
X149606D02*
D03*
X117323Y-65354D02*
D03*
X121467Y-74575D02*
D03*
X-18601Y-349409D02*
D03*
X87795Y-99606D02*
D03*
X540551Y-340945D02*
D03*
X535827Y-345276D02*
D03*
X555512Y-340158D02*
D03*
X544882Y-336221D02*
D03*
X552756Y-335827D02*
D03*
X561024Y-340158D02*
D03*
X568898Y-319009D02*
D03*
X570079Y-309921D02*
D03*
X552756Y-305118D02*
D03*
X544882D02*
D03*
X536221Y-300787D02*
D03*
X530709D02*
D03*
X530315Y-338976D02*
D03*
X513406Y-302902D02*
D03*
X521654Y-336221D02*
D03*
X513386D02*
D03*
X505410Y-336036D02*
D03*
X505512Y-303150D02*
D03*
X455118Y-92520D02*
D03*
X460236Y-87795D02*
D03*
Y-92520D02*
D03*
X454724Y-87795D02*
D03*
X624409Y-31496D02*
D03*
X620079Y-31890D02*
D03*
X615748Y-32283D02*
D03*
X611417Y-33071D02*
D03*
X620866Y-35827D02*
D03*
X611811Y-38189D02*
D03*
X601181Y-23622D02*
D03*
X597244D02*
D03*
Y-29921D02*
D03*
X601181Y-26772D02*
D03*
Y-29921D02*
D03*
X597244Y-26772D02*
D03*
X542913Y-72835D02*
D03*
Y-69291D02*
D03*
Y-65748D02*
D03*
Y-61811D02*
D03*
Y-58268D02*
D03*
X595276Y-79921D02*
D03*
X608405Y-70079D02*
D03*
X618110Y-62205D02*
D03*
X616142Y-47638D02*
D03*
X618898Y-50787D02*
D03*
X613386D02*
D03*
X609547Y-51181D02*
D03*
X606693Y-50787D02*
D03*
X601575Y-53543D02*
D03*
X599213Y-50000D02*
D03*
X544095Y-42126D02*
D03*
X539764D02*
D03*
X534646Y-51968D02*
D03*
X534252Y-48425D02*
D03*
X534646Y-45276D02*
D03*
Y-42126D02*
D03*
X238189Y-107087D02*
D03*
X233071D02*
D03*
X223228Y-107480D02*
D03*
X228346D02*
D03*
X238189Y-138976D02*
D03*
X233209Y-139232D02*
D03*
X228209Y-138721D02*
D03*
X217405Y-138189D02*
D03*
X223209Y-137815D02*
D03*
X214173Y-107087D02*
D03*
X192126Y-111811D02*
D03*
X199193Y-105925D02*
D03*
X204193Y-138257D02*
D03*
X199193Y-138680D02*
D03*
X130245Y-120870D02*
D03*
X133099Y-119984D02*
D03*
X148425Y-104336D02*
D03*
X153150Y-103412D02*
D03*
Y-99691D02*
D03*
X158268Y-107480D02*
D03*
X168110Y-103937D02*
D03*
Y-100132D02*
D03*
X161417Y-95276D02*
D03*
Y-107480D02*
D03*
X178185Y-136811D02*
D03*
Y-133661D02*
D03*
X150627Y-130512D02*
D03*
X150233Y-127362D02*
D03*
X152904Y-124213D02*
D03*
X152398Y-117717D02*
D03*
X156926Y-111614D02*
D03*
X164843Y-114040D02*
D03*
X160075Y-112402D02*
D03*
X168343Y-110827D02*
D03*
X186847Y-135236D02*
D03*
X188028Y-113583D02*
D03*
X189209Y-131339D02*
D03*
Y-117480D02*
D03*
X173461Y-127362D02*
D03*
X165587Y-139961D02*
D03*
X151808Y-137205D02*
D03*
X162241Y-140004D02*
D03*
X106693Y15354D02*
D03*
X107087Y9449D02*
D03*
X111024D02*
D03*
Y15354D02*
D03*
X105512Y-79921D02*
D03*
X109843D02*
D03*
Y-74410D02*
D03*
X105512D02*
D03*
X99606Y-63779D02*
D03*
X107874D02*
D03*
Y-59842D02*
D03*
X99606D02*
D03*
X74616Y-61723D02*
D03*
X56693Y1060D02*
D03*
X39764Y-29528D02*
D03*
Y-25984D02*
D03*
X35731Y-9843D02*
D03*
Y-18898D02*
D03*
X47441Y-27362D02*
D03*
Y-21260D02*
D03*
Y-5709D02*
D03*
Y-11811D02*
D03*
X75394Y-5709D02*
D03*
Y-11811D02*
D03*
X66142D02*
D03*
X61417D02*
D03*
X56693D02*
D03*
Y-16535D02*
D03*
X61417D02*
D03*
X66142D02*
D03*
Y-21260D02*
D03*
X61417D02*
D03*
X52362Y-35531D02*
D03*
X61417Y-35741D02*
D03*
X37402Y-43355D02*
D03*
X38382Y-48355D02*
D03*
X66102Y-64085D02*
D03*
X72795Y-53355D02*
D03*
X86614Y-56299D02*
D03*
X91339Y-35039D02*
D03*
X86614Y-39370D02*
D03*
X88583Y-53937D02*
D03*
X85039D02*
D03*
X88583Y-50787D02*
D03*
X85039D02*
D03*
X88583Y-46457D02*
D03*
X85039Y-46850D02*
D03*
X84252Y-9055D02*
D03*
Y-5906D02*
D03*
Y-2362D02*
D03*
X88257Y-2500D02*
D03*
X93608Y-3379D02*
D03*
X90158Y-7480D02*
D03*
X107832Y-10197D02*
D03*
X97408D02*
D03*
X106693Y-27559D02*
D03*
X105282Y-19291D02*
D03*
X85827Y-16929D02*
D03*
X85853Y-13780D02*
D03*
X78740Y18110D02*
D03*
Y15354D02*
D03*
Y9843D02*
D03*
Y6693D02*
D03*
Y3543D02*
D03*
X110589Y1589D02*
D03*
X108268Y394D02*
D03*
X112598D02*
D03*
X116929Y-21654D02*
D03*
X118898Y-16929D02*
D03*
X366043Y-153937D02*
D03*
X373228Y-162598D02*
D03*
X378346Y-161811D02*
D03*
X388713Y-128731D02*
D03*
X383083Y-128504D02*
D03*
X336221Y-122047D02*
D03*
X333465D02*
D03*
X330315Y-121653D02*
D03*
X335827Y-164173D02*
D03*
X333071D02*
D03*
X329919Y-164008D02*
D03*
X329656Y-142480D02*
D03*
X329722Y-145827D02*
D03*
X347638Y-119882D02*
D03*
X347244Y-113189D02*
D03*
X355035Y-105876D02*
D03*
X390654Y-104510D02*
D03*
X383465Y-103543D02*
D03*
X369685Y-123622D02*
D03*
Y-120866D02*
D03*
Y-118110D02*
D03*
X366929Y-123622D02*
D03*
Y-120866D02*
D03*
X363779Y-123622D02*
D03*
X366929Y-118110D02*
D03*
X363779Y-120866D02*
D03*
Y-118110D02*
D03*
X448425Y-165354D02*
D03*
X451968D02*
D03*
X455512D02*
D03*
X458661D02*
D03*
X442815Y-161747D02*
D03*
Y-165847D02*
D03*
X439561D02*
D03*
X425984Y-109843D02*
D03*
X425630Y-112894D02*
D03*
X416535Y-120768D02*
D03*
X423622Y-115354D02*
D03*
X436811Y-153543D02*
D03*
X418110D02*
D03*
X422835D02*
D03*
X427559D02*
D03*
Y-148819D02*
D03*
X418110D02*
D03*
X422835D02*
D03*
Y-144095D02*
D03*
X418110D02*
D03*
X422835Y-131791D02*
D03*
X427843Y-166966D02*
D03*
X422835Y-166284D02*
D03*
X406693Y-125984D02*
D03*
X408268Y-124409D02*
D03*
Y-122047D02*
D03*
X400984Y-127102D02*
D03*
X415748Y-129609D02*
D03*
X418898Y-129753D02*
D03*
X445276Y-103543D02*
D03*
X444488Y-106299D02*
D03*
X440945Y-105905D02*
D03*
X436221Y-106299D02*
D03*
X434347Y-103743D02*
D03*
X434646Y-100787D02*
D03*
X431496Y-100000D02*
D03*
X422047Y-101969D02*
D03*
X418898Y-100000D02*
D03*
X445669Y-128347D02*
D03*
X449606D02*
D03*
Y-124803D02*
D03*
Y-121653D02*
D03*
X275590Y-199606D02*
D03*
X289370Y-200394D02*
D03*
X274803Y-188583D02*
D03*
X291831Y-197012D02*
D03*
X295669Y-191339D02*
D03*
X292815Y-187106D02*
D03*
X275590Y-184252D02*
D03*
X281890Y-188583D02*
D03*
Y-200771D02*
D03*
X288583Y-195276D02*
D03*
X275503D02*
D03*
X596063Y-239895D02*
D03*
Y-241995D02*
D03*
X321654Y-232677D02*
D03*
X336614Y-286221D02*
D03*
X315945Y-287795D02*
D03*
X315333Y-299430D02*
D03*
X336811Y-299399D02*
D03*
X313386Y-283465D02*
D03*
X308268Y-300000D02*
D03*
X324184Y-302194D02*
D03*
X356693Y-288583D02*
D03*
X355741Y-296063D02*
D03*
X314961Y-293701D02*
D03*
X320472Y-299569D02*
D03*
X325776Y-293701D02*
D03*
X320472Y-287865D02*
D03*
X345161Y-292913D02*
D03*
X333465D02*
D03*
X339370Y-286162D02*
D03*
Y-298819D02*
D03*
X329134Y-228740D02*
D03*
X341274Y-242913D02*
D03*
X340786Y-235827D02*
D03*
X312322Y-236221D02*
D03*
X309782Y-243307D02*
D03*
X334842Y-247244D02*
D03*
X319685Y-245276D02*
D03*
X333714Y-239764D02*
D03*
X325590Y-246324D02*
D03*
Y-232344D02*
D03*
X317009Y-239764D02*
D03*
X390896Y-249065D02*
D03*
X386615Y-249113D02*
D03*
X400000Y-219291D02*
D03*
X398472Y-235531D02*
D03*
X378937Y-249803D02*
D03*
X367654Y-236614D02*
D03*
X373093Y-232972D02*
D03*
X375197Y-221260D02*
D03*
X382776Y-221555D02*
D03*
X368232Y-217717D02*
D03*
X390158D02*
D03*
X415623Y-358391D02*
D03*
X414772Y-353273D02*
D03*
X449150Y-355832D02*
D03*
X460678Y-359179D02*
D03*
X460900Y-354061D02*
D03*
X493234Y-356620D02*
D03*
X533931Y-356296D02*
D03*
X499525Y-358855D02*
D03*
X499302Y-353737D02*
D03*
X579072Y-356690D02*
D03*
X561330Y-356099D02*
D03*
X543698Y-358659D02*
D03*
X543718Y-353540D02*
D03*
X626987Y-228346D02*
D03*
X605512Y-261024D02*
D03*
Y-256693D02*
D03*
X622835Y-244094D02*
D03*
Y-235433D02*
D03*
X618504Y-252362D02*
D03*
X622101Y-250000D02*
D03*
X622803Y-241006D02*
D03*
X605317Y-252756D02*
D03*
X610236Y-300000D02*
D03*
X619148Y-302756D02*
D03*
X622221Y-313481D02*
D03*
X622753Y-353307D02*
D03*
X622677Y-333307D02*
D03*
X623228Y-343307D02*
D03*
X598583Y-353307D02*
D03*
X598819Y-343307D02*
D03*
X598959Y-333307D02*
D03*
X598898Y-313307D02*
D03*
X393701Y-168898D02*
D03*
X378594Y-166966D02*
D03*
X348031Y-165748D02*
D03*
X342808Y-166966D02*
D03*
X337795Y-181102D02*
D03*
X334252Y-180315D02*
D03*
X310236Y-165748D02*
D03*
X309055Y-195669D02*
D03*
X314675Y-198819D02*
D03*
X319291Y-196850D02*
D03*
X322835Y-196063D02*
D03*
X373730Y-202888D02*
D03*
X375698Y-197700D02*
D03*
X383572Y-206205D02*
D03*
X385541Y-202460D02*
D03*
X155427Y-33907D02*
D03*
X155328Y-26033D02*
D03*
X122539D02*
D03*
X142126Y-348031D02*
D03*
X141587Y-352161D02*
D03*
X377658Y-346144D02*
D03*
X256890Y-374655D02*
D03*
X380807Y-346144D02*
D03*
X253655Y-374421D02*
D03*
X269502Y-374291D02*
D03*
X273425Y-374655D02*
D03*
X374114Y-328034D02*
D03*
X371359D02*
D03*
X22047Y-335433D02*
D03*
X2097Y-349213D02*
D03*
X27067Y-282677D02*
D03*
X5584Y-238905D02*
D03*
X35120Y-228937D02*
D03*
X10630Y-197638D02*
D03*
X19976Y-200787D02*
D03*
Y-220472D02*
D03*
X22441Y-167323D02*
D03*
X19685D02*
D03*
X16929D02*
D03*
X23228Y-147244D02*
D03*
X20079D02*
D03*
X17323D02*
D03*
X27165Y-179134D02*
D03*
X-7874Y-188976D02*
D03*
X364173Y-332283D02*
D03*
X370079D02*
D03*
X377658Y-327985D02*
D03*
X369703Y-326432D02*
D03*
X344882Y-328346D02*
D03*
X348425Y-328740D02*
D03*
X381989Y-348458D02*
D03*
X376870D02*
D03*
X374902D02*
D03*
X370472Y-348425D02*
D03*
X368294Y-348913D02*
D03*
X363878Y-348458D02*
D03*
X361910D02*
D03*
X356792D02*
D03*
X349705Y-348064D02*
D03*
X354823Y-348851D02*
D03*
X156693Y-18110D02*
D03*
X203689Y-248906D02*
D03*
X203937Y-242913D02*
D03*
X451674Y-283940D02*
D03*
X381989Y-331971D02*
D03*
X370178Y-315042D02*
D03*
X342618Y-315081D02*
D03*
X451674Y-234727D02*
D03*
X258702Y-264859D02*
D03*
X445768Y-254381D02*
D03*
X359874Y-183841D02*
D03*
X263322Y-246466D02*
D03*
X340847Y-179215D02*
D03*
X451674Y-244570D02*
D03*
X258760Y-256529D02*
D03*
X445768Y-264255D02*
D03*
X350327Y-183546D02*
D03*
X263622Y-236666D02*
D03*
X352461Y-315042D02*
D03*
X330705Y-179215D02*
D03*
X263122Y-285766D02*
D03*
X364272Y-315042D02*
D03*
X343012Y-332365D02*
D03*
X451674Y-254381D02*
D03*
X350327Y-179215D02*
D03*
X258622Y-246466D02*
D03*
X322933Y-332365D02*
D03*
X445768Y-275261D02*
D03*
X340256Y-183841D02*
D03*
X263580Y-226943D02*
D03*
X445768Y-224885D02*
D03*
X320473Y-179117D02*
D03*
X263322Y-276066D02*
D03*
X352106Y-332482D02*
D03*
X451674Y-264255D02*
D03*
X259022Y-236566D02*
D03*
X322540Y-315042D02*
D03*
X445768Y-283940D02*
D03*
X331091Y-184050D02*
D03*
X258622Y-285766D02*
D03*
X376477Y-315042D02*
D03*
X357973Y-315042D02*
D03*
X445768Y-234727D02*
D03*
X379496Y-183803D02*
D03*
Y-179215D02*
D03*
X262922Y-265040D02*
D03*
X332776Y-332365D02*
D03*
X451674Y-275261D02*
D03*
X369981Y-179215D02*
D03*
X258922Y-226766D02*
D03*
X451674Y-224885D02*
D03*
X360138Y-179215D02*
D03*
X258622Y-276066D02*
D03*
X381595Y-315042D02*
D03*
X445768Y-244570D02*
D03*
X369685Y-183841D02*
D03*
X263681Y-256529D02*
D03*
X332382Y-315042D02*
D03*
X19976Y-252953D02*
D03*
Y-272638D02*
D03*
Y-326772D02*
D03*
Y-307087D02*
D03*
X100729Y-123872D02*
D03*
X163071Y-390730D02*
D03*
X259285Y-390247D02*
D03*
X267204Y-390009D02*
D03*
X216162Y-390947D02*
D03*
X235144Y-390416D02*
D03*
X251456Y-390009D02*
D03*
X226063Y-390722D02*
D03*
X281201Y-390009D02*
D03*
X174941Y-390600D02*
D03*
X202441D02*
D03*
X-23622Y-187992D02*
D03*
X26772Y-348819D02*
D03*
X-1181Y-352831D02*
D03*
X4331Y-344488D02*
D03*
X12598Y-349213D02*
D03*
X35039Y-289961D02*
D03*
Y-285827D02*
D03*
X27067Y-298727D02*
D03*
X10630Y-292126D02*
D03*
X14173Y-294320D02*
D03*
X288Y-234968D02*
D03*
X10007D02*
D03*
X19685Y-239370D02*
D03*
X14665Y-237402D02*
D03*
X36220Y-235039D02*
D03*
X36614Y-232677D02*
D03*
X35039Y-237402D02*
D03*
X30709Y-190411D02*
D03*
X33071Y-185755D02*
D03*
X35827D02*
D03*
X13780Y-190551D02*
D03*
X9843Y-185755D02*
D03*
X19682Y-192520D02*
D03*
X-10630Y-178347D02*
D03*
X198392Y-366842D02*
D03*
X196701Y-370523D02*
D03*
X394193Y-197670D02*
D03*
X380363Y-196740D02*
D03*
X157480Y-361811D02*
D03*
X153543Y-358661D02*
D03*
Y-361811D02*
D03*
X155512D02*
D03*
Y-358661D02*
D03*
X157480D02*
D03*
X157087Y-41732D02*
D03*
X230165Y-235119D02*
D03*
X246162Y-293733D02*
D03*
X230406Y-251861D02*
D03*
X230251Y-232266D02*
D03*
X204331Y-232677D02*
D03*
X203937Y-235827D02*
D03*
Y-238189D02*
D03*
X203805Y-240564D02*
D03*
X203805Y-252182D02*
D03*
X203937Y-254724D02*
D03*
X154724Y-389616D02*
D03*
X156693D02*
D03*
X158661D02*
D03*
X154724Y-386466D02*
D03*
X156693D02*
D03*
X158661D02*
D03*
X280414Y-293782D02*
D03*
X245965Y-264497D02*
D03*
Y-254655D02*
D03*
X432835Y-291755D02*
D03*
X472047Y-221260D02*
D03*
X430020Y-218979D02*
D03*
X472047Y-223228D02*
D03*
X430020Y-220948D02*
D03*
Y-222916D02*
D03*
X472047Y-219291D02*
D03*
X430020Y-217010D02*
D03*
X121457Y-57529D02*
D03*
X280382Y-274277D02*
D03*
X337774Y-196489D02*
D03*
X274719Y-244928D02*
D03*
X276755Y-246539D02*
D03*
X280414Y-283478D02*
D03*
Y-287478D02*
D03*
X331220Y-196266D02*
D03*
X341774Y-196326D02*
D03*
X326705Y-179059D02*
D03*
X324705Y-184678D02*
D03*
X463453Y-247883D02*
D03*
X464472Y-245540D02*
D03*
X327658Y-184678D02*
D03*
X36614Y18701D02*
D03*
X244028Y-262466D02*
D03*
Y-258497D02*
D03*
X243996Y-252592D02*
D03*
X245965Y-250655D02*
D03*
X243996Y-248655D02*
D03*
X245965Y-260497D02*
D03*
X-23622Y-342520D02*
D03*
X100729Y-119871D02*
D03*
X-23622Y-229331D02*
D03*
Y-233268D02*
D03*
Y-237205D02*
D03*
Y-241142D02*
D03*
Y-282480D02*
D03*
Y-286417D02*
D03*
Y-290354D02*
D03*
Y-294291D02*
D03*
Y-335630D02*
D03*
Y-339567D02*
D03*
Y-66929D02*
D03*
Y-62992D02*
D03*
Y-60039D02*
D03*
Y-102362D02*
D03*
Y-106299D02*
D03*
Y-110236D02*
D03*
Y-184055D02*
D03*
Y-177165D02*
D03*
X472047Y-217323D02*
D03*
X190354Y-377411D02*
D03*
X178543D02*
D03*
X362598Y-197244D02*
D03*
X36762Y11811D02*
D03*
X36614Y4921D02*
D03*
Y-1969D02*
D03*
X389567Y-196440D02*
D03*
X432579Y-283251D02*
D03*
Y-286400D02*
D03*
X432720Y-289358D02*
D03*
D251*
X127392Y-94557D02*
D03*
X365581Y7806D02*
D03*
Y-94557D02*
D03*
X127392Y7806D02*
D03*
X479695Y-331073D02*
D03*
X582058Y-92884D02*
D03*
X479695D02*
D03*
X582058Y-331073D02*
D03*
M02*
